FILE_TYPE = MACRO_DRAWING;
SET COLOR_WIRE YELLOW;
SET COLOR_PROP ORANGE;
SET COLOR_DOT WHITE;
SET COLOR_ARC YELLOW;
SET COLOR_BODY GREEN;
SET COLOR_NOTE PURPLE;
SET PROP_DISPLAY VALUE;
SET PAGE_NUMBER P83;
FORCEADD UNIVERSAL_GND..1
(-8375 2925);
FORCEPROP 3 LASTPIN (-8375 2975) SIG_NAME GND\g
J 0
(-8365 2985);
DISPLAY 0.659574 (-8365 2985);
PAINT MONO (-8365 2985);
DISPLAY INVISIBLE (-8365 2985);
FORCEPROP 2 LAST BOM_COST OCP3.0 
J 0
(-8575 3000);
DISPLAY 0.680851 (-8575 3000);
DISPLAY INVISIBLE (-8575 3000);
FORCEPROP 2 LAST CDS_LIB pure_quanta_power
J 0
(-8375 2925);
DISPLAY INVISIBLE (-8375 2925);
FORCEPROP 1 LAST HDL_POWER GND
J 1
(-8350 2850);
DISPLAY 0.872340 (-8350 2850);
PAINT GREEN (-8350 2850);
DISPLAY INVISIBLE (-8350 2850);
FORCEPROP 1 LAST PATH I100
J 0
(-8300 2925);
DISPLAY 0.872340 (-8300 2925);
PAINT AQUA (-8300 2925);
DISPLAY INVISIBLE (-8300 2925);
FORCEADD UNIVERSAL_GND..1
(-8050 2925);
FORCEPROP 3 LASTPIN (-8050 2975) SIG_NAME GND\g
J 0
(-8040 2985);
DISPLAY 0.659574 (-8040 2985);
PAINT MONO (-8040 2985);
DISPLAY INVISIBLE (-8040 2985);
FORCEPROP 2 LAST BOM_COST OCP3.0 
J 0
(-8250 3000);
DISPLAY 0.680851 (-8250 3000);
DISPLAY INVISIBLE (-8250 3000);
FORCEPROP 2 LAST CDS_LIB pure_quanta_power
J 0
(-8050 2925);
DISPLAY INVISIBLE (-8050 2925);
FORCEPROP 1 LAST HDL_POWER GND
J 1
(-8025 2850);
DISPLAY 0.872340 (-8025 2850);
PAINT GREEN (-8025 2850);
DISPLAY INVISIBLE (-8025 2850);
FORCEPROP 1 LAST PATH I101
J 0
(-7975 2925);
DISPLAY 0.872340 (-7975 2925);
PAINT AQUA (-7975 2925);
DISPLAY INVISIBLE (-7975 2925);
FORCEADD UNIVERSAL_GND..1
(-7700 2925);
FORCEPROP 3 LASTPIN (-7700 2975) SIG_NAME GND\g
J 0
(-7690 2985);
DISPLAY 0.659574 (-7690 2985);
PAINT MONO (-7690 2985);
DISPLAY INVISIBLE (-7690 2985);
FORCEPROP 2 LAST BOM_COST OCP3.0 
J 0
(-7900 3000);
DISPLAY 0.680851 (-7900 3000);
DISPLAY INVISIBLE (-7900 3000);
FORCEPROP 2 LAST CDS_LIB pure_quanta_power
J 0
(-7700 2925);
DISPLAY INVISIBLE (-7700 2925);
FORCEPROP 1 LAST HDL_POWER GND
J 1
(-7675 2850);
DISPLAY 0.872340 (-7675 2850);
PAINT GREEN (-7675 2850);
DISPLAY INVISIBLE (-7675 2850);
FORCEPROP 1 LAST PATH I102
J 0
(-7625 2925);
DISPLAY 0.872340 (-7625 2925);
PAINT AQUA (-7625 2925);
DISPLAY INVISIBLE (-7625 2925);
FORCEADD UNIVERSAL_GND..1
(-7350 2925);
FORCEPROP 3 LASTPIN (-7350 2975) SIG_NAME GND\g
J 0
(-7340 2985);
DISPLAY 0.659574 (-7340 2985);
PAINT MONO (-7340 2985);
DISPLAY INVISIBLE (-7340 2985);
FORCEPROP 2 LAST BOM_COST OCP3.0 
J 0
(-7550 3000);
DISPLAY 0.680851 (-7550 3000);
DISPLAY INVISIBLE (-7550 3000);
FORCEPROP 2 LAST CDS_LIB pure_quanta_power
J 0
(-7350 2925);
DISPLAY INVISIBLE (-7350 2925);
FORCEPROP 1 LAST HDL_POWER GND
J 1
(-7325 2850);
DISPLAY 0.872340 (-7325 2850);
PAINT GREEN (-7325 2850);
DISPLAY INVISIBLE (-7325 2850);
FORCEPROP 1 LAST PATH I103
J 0
(-7275 2925);
DISPLAY 0.872340 (-7275 2925);
PAINT AQUA (-7275 2925);
DISPLAY INVISIBLE (-7275 2925);
FORCEADD UNIVERSAL_GND..1
(-8700 650);
FORCEPROP 3 LASTPIN (-8700 700) SIG_NAME GND\g
J 0
(-8690 710);
DISPLAY 0.659574 (-8690 710);
PAINT MONO (-8690 710);
DISPLAY INVISIBLE (-8690 710);
FORCEPROP 2 LAST BOM_COST OCP3.0 
J 0
(-8900 725);
DISPLAY 0.680851 (-8900 725);
DISPLAY INVISIBLE (-8900 725);
FORCEPROP 2 LAST CDS_LIB pure_quanta_power
J 0
(-8700 650);
DISPLAY INVISIBLE (-8700 650);
FORCEPROP 1 LAST HDL_POWER GND
J 1
(-8675 575);
DISPLAY 0.872340 (-8675 575);
PAINT GREEN (-8675 575);
DISPLAY INVISIBLE (-8675 575);
FORCEPROP 1 LAST PATH I104
J 0
(-8625 650);
DISPLAY 0.872340 (-8625 650);
PAINT AQUA (-8625 650);
DISPLAY INVISIBLE (-8625 650);
FORCEADD UNIVERSAL_GND..1
(-8375 650);
FORCEPROP 3 LASTPIN (-8375 700) SIG_NAME GND\g
J 0
(-8365 710);
DISPLAY 0.659574 (-8365 710);
PAINT MONO (-8365 710);
DISPLAY INVISIBLE (-8365 710);
FORCEPROP 2 LAST BOM_COST OCP3.0 
J 0
(-8575 725);
DISPLAY 0.680851 (-8575 725);
DISPLAY INVISIBLE (-8575 725);
FORCEPROP 2 LAST CDS_LIB pure_quanta_power
J 0
(-8375 650);
DISPLAY INVISIBLE (-8375 650);
FORCEPROP 1 LAST HDL_POWER GND
J 1
(-8350 575);
DISPLAY 0.872340 (-8350 575);
PAINT GREEN (-8350 575);
DISPLAY INVISIBLE (-8350 575);
FORCEPROP 1 LAST PATH I105
J 0
(-8300 650);
DISPLAY 0.872340 (-8300 650);
PAINT AQUA (-8300 650);
DISPLAY INVISIBLE (-8300 650);
FORCEADD UNIVERSAL_GND..1
(-8050 650);
FORCEPROP 3 LASTPIN (-8050 700) SIG_NAME GND\g
J 0
(-8040 710);
DISPLAY 0.659574 (-8040 710);
PAINT MONO (-8040 710);
DISPLAY INVISIBLE (-8040 710);
FORCEPROP 2 LAST BOM_COST OCP3.0 
J 0
(-8250 725);
DISPLAY 0.680851 (-8250 725);
DISPLAY INVISIBLE (-8250 725);
FORCEPROP 2 LAST CDS_LIB pure_quanta_power
J 0
(-8050 650);
DISPLAY INVISIBLE (-8050 650);
FORCEPROP 1 LAST HDL_POWER GND
J 1
(-8025 575);
DISPLAY 0.872340 (-8025 575);
PAINT GREEN (-8025 575);
DISPLAY INVISIBLE (-8025 575);
FORCEPROP 1 LAST PATH I106
J 0
(-7975 650);
DISPLAY 0.872340 (-7975 650);
PAINT AQUA (-7975 650);
DISPLAY INVISIBLE (-7975 650);
FORCEADD UNIVERSAL_GND..1
(-7700 650);
FORCEPROP 3 LASTPIN (-7700 700) SIG_NAME GND\g
J 0
(-7690 710);
DISPLAY 0.659574 (-7690 710);
PAINT MONO (-7690 710);
DISPLAY INVISIBLE (-7690 710);
FORCEPROP 2 LAST BOM_COST OCP3.0 
J 0
(-7900 725);
DISPLAY 0.680851 (-7900 725);
DISPLAY INVISIBLE (-7900 725);
FORCEPROP 2 LAST CDS_LIB pure_quanta_power
J 0
(-7700 650);
DISPLAY INVISIBLE (-7700 650);
FORCEPROP 1 LAST HDL_POWER GND
J 1
(-7675 575);
DISPLAY 0.872340 (-7675 575);
PAINT GREEN (-7675 575);
DISPLAY INVISIBLE (-7675 575);
FORCEPROP 1 LAST PATH I107
J 0
(-7625 650);
DISPLAY 0.872340 (-7625 650);
PAINT AQUA (-7625 650);
DISPLAY INVISIBLE (-7625 650);
FORCEADD UNIVERSAL_GND..1
(-7350 650);
FORCEPROP 3 LASTPIN (-7350 700) SIG_NAME GND\g
J 0
(-7340 710);
DISPLAY 0.659574 (-7340 710);
PAINT MONO (-7340 710);
DISPLAY INVISIBLE (-7340 710);
FORCEPROP 2 LAST BOM_COST OCP3.0 
J 0
(-7550 725);
DISPLAY 0.680851 (-7550 725);
DISPLAY INVISIBLE (-7550 725);
FORCEPROP 2 LAST CDS_LIB pure_quanta_power
J 0
(-7350 650);
DISPLAY INVISIBLE (-7350 650);
FORCEPROP 1 LAST HDL_POWER GND
J 1
(-7325 575);
DISPLAY 0.872340 (-7325 575);
PAINT GREEN (-7325 575);
DISPLAY INVISIBLE (-7325 575);
FORCEPROP 1 LAST PATH I108
J 0
(-7275 650);
DISPLAY 0.872340 (-7275 650);
PAINT AQUA (-7275 650);
DISPLAY INVISIBLE (-7275 650);
FORCEADD UNIVERSAL_GND..1
(-3650 3225);
FORCEPROP 3 LASTPIN (-3650 3275) SIG_NAME GND\g
J 0
(-3640 3285);
DISPLAY 0.659574 (-3640 3285);
PAINT MONO (-3640 3285);
DISPLAY INVISIBLE (-3640 3285);
FORCEPROP 2 LAST CDS_LIB pure_quanta_power
J 0
(-3650 3225);
DISPLAY INVISIBLE (-3650 3225);
FORCEPROP 2 LAST BOM_COST OCP3.0 
J 0
(-3850 3300);
DISPLAY 0.680851 (-3850 3300);
DISPLAY INVISIBLE (-3850 3300);
FORCEPROP 1 LAST HDL_POWER GND
J 1
(-3625 3150);
DISPLAY 0.872340 (-3625 3150);
PAINT GREEN (-3625 3150);
DISPLAY INVISIBLE (-3625 3150);
FORCEPROP 1 LAST PATH I109
J 0
(-3575 3225);
DISPLAY 0.872340 (-3575 3225);
PAINT AQUA (-3575 3225);
DISPLAY INVISIBLE (-3575 3225);
FORCEADD UNIVERSAL_GND..1
(-3300 3225);
FORCEPROP 3 LASTPIN (-3300 3275) SIG_NAME GND\g
J 0
(-3290 3285);
DISPLAY 0.659574 (-3290 3285);
PAINT MONO (-3290 3285);
DISPLAY INVISIBLE (-3290 3285);
FORCEPROP 2 LAST CDS_LIB pure_quanta_power
J 0
(-3300 3225);
DISPLAY INVISIBLE (-3300 3225);
FORCEPROP 2 LAST BOM_COST OCP3.0 
J 0
(-3500 3300);
DISPLAY 0.680851 (-3500 3300);
DISPLAY INVISIBLE (-3500 3300);
FORCEPROP 1 LAST HDL_POWER GND
J 1
(-3275 3150);
DISPLAY 0.872340 (-3275 3150);
PAINT GREEN (-3275 3150);
DISPLAY INVISIBLE (-3275 3150);
FORCEPROP 1 LAST PATH I110
J 0
(-3225 3225);
DISPLAY 0.872340 (-3225 3225);
PAINT AQUA (-3225 3225);
DISPLAY INVISIBLE (-3225 3225);
FORCEADD UNIVERSAL_GND..1
(-2950 3225);
FORCEPROP 3 LASTPIN (-2950 3275) SIG_NAME GND\g
J 0
(-2940 3285);
DISPLAY 0.659574 (-2940 3285);
PAINT MONO (-2940 3285);
DISPLAY INVISIBLE (-2940 3285);
FORCEPROP 2 LAST CDS_LIB pure_quanta_power
J 0
(-2950 3225);
DISPLAY INVISIBLE (-2950 3225);
FORCEPROP 2 LAST BOM_COST OCP3.0 
J 0
(-3150 3300);
DISPLAY 0.680851 (-3150 3300);
DISPLAY INVISIBLE (-3150 3300);
FORCEPROP 1 LAST HDL_POWER GND
J 1
(-2925 3150);
DISPLAY 0.872340 (-2925 3150);
PAINT GREEN (-2925 3150);
DISPLAY INVISIBLE (-2925 3150);
FORCEPROP 1 LAST PATH I111
J 0
(-2875 3225);
DISPLAY 0.872340 (-2875 3225);
PAINT AQUA (-2875 3225);
DISPLAY INVISIBLE (-2875 3225);
FORCEADD UNIVERSAL_GND..1
(-3650 575);
FORCEPROP 3 LASTPIN (-3650 625) SIG_NAME GND\g
J 0
(-3640 635);
DISPLAY 0.659574 (-3640 635);
PAINT MONO (-3640 635);
DISPLAY INVISIBLE (-3640 635);
FORCEPROP 2 LAST BOM_COST OCP3.0 
J 0
(-3850 650);
DISPLAY 0.680851 (-3850 650);
DISPLAY INVISIBLE (-3850 650);
FORCEPROP 2 LAST CDS_LIB pure_quanta_power
J 0
(-3650 575);
DISPLAY INVISIBLE (-3650 575);
FORCEPROP 1 LAST HDL_POWER GND
J 1
(-3625 500);
DISPLAY 0.872340 (-3625 500);
PAINT GREEN (-3625 500);
DISPLAY INVISIBLE (-3625 500);
FORCEPROP 1 LAST PATH I112
J 0
(-3575 575);
DISPLAY 0.872340 (-3575 575);
PAINT AQUA (-3575 575);
DISPLAY INVISIBLE (-3575 575);
FORCEADD UNIVERSAL_GND..1
(-3300 575);
FORCEPROP 3 LASTPIN (-3300 625) SIG_NAME GND\g
J 0
(-3290 635);
DISPLAY 0.659574 (-3290 635);
PAINT MONO (-3290 635);
DISPLAY INVISIBLE (-3290 635);
FORCEPROP 2 LAST BOM_COST OCP3.0 
J 0
(-3500 650);
DISPLAY 0.680851 (-3500 650);
DISPLAY INVISIBLE (-3500 650);
FORCEPROP 2 LAST CDS_LIB pure_quanta_power
J 0
(-3300 575);
DISPLAY INVISIBLE (-3300 575);
FORCEPROP 1 LAST HDL_POWER GND
J 1
(-3275 500);
DISPLAY 0.872340 (-3275 500);
PAINT GREEN (-3275 500);
DISPLAY INVISIBLE (-3275 500);
FORCEPROP 1 LAST PATH I113
J 0
(-3225 575);
DISPLAY 0.872340 (-3225 575);
PAINT AQUA (-3225 575);
DISPLAY INVISIBLE (-3225 575);
FORCEADD UNIVERSAL_GND..1
(-2950 575);
FORCEPROP 3 LASTPIN (-2950 625) SIG_NAME GND\g
J 0
(-2940 635);
DISPLAY 0.659574 (-2940 635);
PAINT MONO (-2940 635);
DISPLAY INVISIBLE (-2940 635);
FORCEPROP 2 LAST BOM_COST OCP3.0 
J 0
(-3150 650);
DISPLAY 0.680851 (-3150 650);
DISPLAY INVISIBLE (-3150 650);
FORCEPROP 2 LAST CDS_LIB pure_quanta_power
J 0
(-2950 575);
DISPLAY INVISIBLE (-2950 575);
FORCEPROP 1 LAST HDL_POWER GND
J 1
(-2925 500);
DISPLAY 0.872340 (-2925 500);
PAINT GREEN (-2925 500);
DISPLAY INVISIBLE (-2925 500);
FORCEPROP 1 LAST PATH I114
J 0
(-2875 575);
DISPLAY 0.872340 (-2875 575);
PAINT AQUA (-2875 575);
DISPLAY INVISIBLE (-2875 575);
FORCEADD Q_RES..2
(-8700 4350);
FORCEPROP 1 LAST LOCATION R6120
J 0
(-8655 4475);
DISPLAY 0.978723 (-8655 4475);
FORCEPROP 0 LAST $SEC 1
J 0
(-8650 4525);
DISPLAY 0.680851 (-8650 4525);
PAINT MONO (-8650 4525);
DISPLAY INVISIBLE (-8650 4525);
FORCEPROP 0 LAST CDS_SEC 1
J 0
(-8650 4525);
DISPLAY 0.680851 (-8650 4525);
DISPLAY INVISIBLE (-8650 4525);
FORCEPROP 1 LASTPIN (-8700 4450) $PN 1
J 0
(-8695 4412);
DISPLAY 0.787234 (-8695 4412);
PAINT MONO (-8695 4412);
FORCEPROP 1 LASTPIN (-8700 4250) $PN 2
J 0
(-8695 4260);
DISPLAY 0.787234 (-8695 4260);
PAINT MONO (-8695 4260);
FORCEPROP 1 LAST TOLERANCE 1%
J 0
(-8655 4375);
DISPLAY 0.978723 (-8655 4375);
FORCEPROP 1 LAST VALUE 1K
J 0
(-8655 4425);
DISPLAY 0.978723 (-8655 4425);
FORCEPROP 1 LAST WATTAGE 1/16W
J 0
(-8660 4325);
DISPLAY 0.978723 (-8660 4325);
FORCEPROP 1 LAST MATERIAL CHIP
J 0
(-8660 4275);
DISPLAY 0.978723 (-8660 4275);
FORCEPROP 1 LAST PACK_TYPE 0402LF
J 0
(-8650 4225);
DISPLAY 0.978723 (-8650 4225);
FORCEPROP 2 LAST CDS_LIB pure_quanta
J 0
(-8700 4350);
DISPLAY INVISIBLE (-8700 4350);
FORCEPROP 1 LAST PATH I115
J 0
(-8650 4525);
DISPLAY 0.978723 (-8650 4525);
PAINT WHITE (-8650 4525);
DISPLAY INVISIBLE (-8650 4525);
FORCEPROP 1 LAST PART_NUMBER CS21002FB06
J 0
(-8660 4225);
DISPLAY 0.978723 (-8660 4225);
DISPLAY INVISIBLE (-8660 4225);
FORCEADD Q_RES..2
(-8700 3400);
FORCEPROP 1 LAST LOCATION R6125
J 0
(-8655 3525);
DISPLAY 0.978723 (-8655 3525);
FORCEPROP 0 LAST $SEC 1
J 0
(-8650 3575);
DISPLAY 0.680851 (-8650 3575);
PAINT MONO (-8650 3575);
DISPLAY INVISIBLE (-8650 3575);
FORCEPROP 0 LAST CDS_SEC 1
J 0
(-8650 3575);
DISPLAY 0.680851 (-8650 3575);
DISPLAY INVISIBLE (-8650 3575);
FORCEPROP 1 LASTPIN (-8700 3500) $PN 1
J 0
(-8695 3462);
DISPLAY 0.787234 (-8695 3462);
PAINT MONO (-8695 3462);
FORCEPROP 1 LASTPIN (-8700 3300) $PN 2
J 0
(-8695 3310);
DISPLAY 0.787234 (-8695 3310);
PAINT MONO (-8695 3310);
FORCEPROP 1 LAST MATERIAL EMPTY
J 0
(-8660 3325);
DISPLAY 0.978723 (-8660 3325);
FORCEPROP 1 LAST PACK_TYPE 0402LF
J 0
(-8650 3275);
DISPLAY 0.978723 (-8650 3275);
FORCEPROP 1 LAST WATTAGE 1/16W
J 0
(-8660 3375);
DISPLAY 0.978723 (-8660 3375);
FORCEPROP 1 LAST TOLERANCE 1%
J 0
(-8655 3425);
DISPLAY 0.978723 (-8655 3425);
FORCEPROP 1 LAST VALUE 1K
J 0
(-8655 3475);
DISPLAY 0.978723 (-8655 3475);
FORCEPROP 2 LAST CDS_LIB pure_quanta
J 0
(-8700 3400);
DISPLAY INVISIBLE (-8700 3400);
FORCEPROP 1 LAST PATH I116
J 0
(-8650 3575);
DISPLAY 0.978723 (-8650 3575);
PAINT WHITE (-8650 3575);
DISPLAY INVISIBLE (-8650 3575);
FORCEPROP 1 LAST PART_NUMBER CS21002FB06
J 0
(-8660 3275);
DISPLAY 0.978723 (-8660 3275);
DISPLAY INVISIBLE (-8660 3275);
FORCEADD Q_RES..2
(-8700 2075);
FORCEPROP 1 LAST LOCATION R6136
J 0
(-8655 2200);
DISPLAY 0.978723 (-8655 2200);
FORCEPROP 0 LAST $SEC 1
J 0
(-8650 2250);
DISPLAY 0.680851 (-8650 2250);
PAINT MONO (-8650 2250);
DISPLAY INVISIBLE (-8650 2250);
FORCEPROP 0 LAST CDS_SEC 1
J 0
(-8650 2250);
DISPLAY 0.680851 (-8650 2250);
DISPLAY INVISIBLE (-8650 2250);
FORCEPROP 1 LASTPIN (-8700 2175) $PN 1
J 0
(-8695 2137);
DISPLAY 0.787234 (-8695 2137);
PAINT MONO (-8695 2137);
FORCEPROP 1 LASTPIN (-8700 1975) $PN 2
J 0
(-8695 1985);
DISPLAY 0.787234 (-8695 1985);
PAINT MONO (-8695 1985);
FORCEPROP 1 LAST TOLERANCE 1%
J 0
(-8655 2100);
DISPLAY 0.978723 (-8655 2100);
FORCEPROP 1 LAST MATERIAL CHIP
J 0
(-8660 2000);
DISPLAY 0.978723 (-8660 2000);
FORCEPROP 1 LAST PACK_TYPE 0402LF
J 0
(-8650 1950);
DISPLAY 0.978723 (-8650 1950);
FORCEPROP 1 LAST VALUE 1K
J 0
(-8655 2150);
DISPLAY 0.978723 (-8655 2150);
FORCEPROP 1 LAST WATTAGE 1/16W
J 0
(-8660 2050);
DISPLAY 0.978723 (-8660 2050);
FORCEPROP 2 LAST CDS_LIB pure_quanta
J 0
(-8700 2075);
DISPLAY INVISIBLE (-8700 2075);
FORCEPROP 1 LAST PATH I117
J 0
(-8650 2250);
DISPLAY 0.978723 (-8650 2250);
PAINT WHITE (-8650 2250);
DISPLAY INVISIBLE (-8650 2250);
FORCEPROP 1 LAST PART_NUMBER CS21002FB06
J 0
(-8660 1950);
DISPLAY 0.978723 (-8660 1950);
DISPLAY INVISIBLE (-8660 1950);
FORCEADD Q_RES..2
(-8700 1125);
FORCEPROP 1 LAST LOCATION R6141
J 0
(-8655 1250);
DISPLAY 0.978723 (-8655 1250);
FORCEPROP 0 LAST $SEC 1
J 0
(-8650 1300);
DISPLAY 0.680851 (-8650 1300);
PAINT MONO (-8650 1300);
DISPLAY INVISIBLE (-8650 1300);
FORCEPROP 0 LAST CDS_SEC 1
J 0
(-8650 1300);
DISPLAY 0.680851 (-8650 1300);
DISPLAY INVISIBLE (-8650 1300);
FORCEPROP 1 LASTPIN (-8700 1225) $PN 1
J 0
(-8695 1187);
DISPLAY 0.787234 (-8695 1187);
PAINT MONO (-8695 1187);
FORCEPROP 1 LASTPIN (-8700 1025) $PN 2
J 0
(-8695 1035);
DISPLAY 0.787234 (-8695 1035);
PAINT MONO (-8695 1035);
FORCEPROP 1 LAST PACK_TYPE 0402LF
J 0
(-8650 1000);
DISPLAY 0.978723 (-8650 1000);
FORCEPROP 1 LAST MATERIAL EMPTY
J 0
(-8660 1050);
DISPLAY 0.978723 (-8660 1050);
FORCEPROP 1 LAST WATTAGE 1/16W
J 0
(-8660 1100);
DISPLAY 0.978723 (-8660 1100);
FORCEPROP 1 LAST TOLERANCE 1%
J 0
(-8655 1150);
DISPLAY 0.978723 (-8655 1150);
FORCEPROP 1 LAST VALUE 1K
J 0
(-8655 1200);
DISPLAY 0.978723 (-8655 1200);
FORCEPROP 2 LAST CDS_LIB pure_quanta
J 0
(-8700 1125);
DISPLAY INVISIBLE (-8700 1125);
FORCEPROP 1 LAST PATH I118
J 0
(-8650 1300);
DISPLAY 0.978723 (-8650 1300);
PAINT WHITE (-8650 1300);
DISPLAY INVISIBLE (-8650 1300);
FORCEPROP 1 LAST PART_NUMBER CS21002FB06
J 0
(-8660 1000);
DISPLAY 0.978723 (-8660 1000);
DISPLAY INVISIBLE (-8660 1000);
FORCEADD Q_RES..2
(-8375 3400);
FORCEPROP 1 LAST LOCATION R6126
J 0
(-8330 3525);
DISPLAY 0.978723 (-8330 3525);
FORCEPROP 0 LAST $SEC 1
J 0
(-8325 3575);
DISPLAY 0.680851 (-8325 3575);
PAINT MONO (-8325 3575);
DISPLAY INVISIBLE (-8325 3575);
FORCEPROP 0 LAST CDS_SEC 1
J 0
(-8325 3575);
DISPLAY 0.680851 (-8325 3575);
DISPLAY INVISIBLE (-8325 3575);
FORCEPROP 1 LASTPIN (-8375 3500) $PN 1
J 0
(-8370 3462);
DISPLAY 0.787234 (-8370 3462);
PAINT MONO (-8370 3462);
FORCEPROP 1 LASTPIN (-8375 3300) $PN 2
J 0
(-8370 3310);
DISPLAY 0.787234 (-8370 3310);
PAINT MONO (-8370 3310);
FORCEPROP 1 LAST VALUE 1K
J 0
(-8330 3475);
DISPLAY 0.978723 (-8330 3475);
FORCEPROP 1 LAST TOLERANCE 1%
J 0
(-8330 3425);
DISPLAY 0.978723 (-8330 3425);
FORCEPROP 1 LAST MATERIAL CHIP
J 0
(-8335 3325);
DISPLAY 0.978723 (-8335 3325);
FORCEPROP 1 LAST PACK_TYPE 0402LF
J 0
(-8325 3275);
DISPLAY 0.978723 (-8325 3275);
FORCEPROP 1 LAST WATTAGE 1/16W
J 0
(-8335 3375);
DISPLAY 0.978723 (-8335 3375);
FORCEPROP 2 LAST CDS_LIB pure_quanta
J 0
(-8375 3400);
DISPLAY INVISIBLE (-8375 3400);
FORCEPROP 1 LAST PATH I119
J 0
(-8325 3575);
DISPLAY 0.978723 (-8325 3575);
PAINT WHITE (-8325 3575);
DISPLAY INVISIBLE (-8325 3575);
FORCEPROP 1 LAST PART_NUMBER CS21002FB06
J 0
(-8335 3275);
DISPLAY 0.978723 (-8335 3275);
DISPLAY INVISIBLE (-8335 3275);
FORCEADD Q_RES..2
(-8375 4350);
FORCEPROP 1 LAST LOCATION R6121
J 0
(-8330 4475);
DISPLAY 0.978723 (-8330 4475);
FORCEPROP 0 LAST $SEC 1
J 0
(-8325 4525);
DISPLAY 0.680851 (-8325 4525);
PAINT MONO (-8325 4525);
DISPLAY INVISIBLE (-8325 4525);
FORCEPROP 0 LAST CDS_SEC 1
J 0
(-8325 4525);
DISPLAY 0.680851 (-8325 4525);
DISPLAY INVISIBLE (-8325 4525);
FORCEPROP 1 LASTPIN (-8375 4450) $PN 1
J 0
(-8370 4412);
DISPLAY 0.787234 (-8370 4412);
PAINT MONO (-8370 4412);
FORCEPROP 1 LASTPIN (-8375 4250) $PN 2
J 0
(-8370 4260);
DISPLAY 0.787234 (-8370 4260);
PAINT MONO (-8370 4260);
FORCEPROP 1 LAST WATTAGE 1/16W
J 0
(-8335 4325);
DISPLAY 0.978723 (-8335 4325);
FORCEPROP 1 LAST PACK_TYPE 0402LF
J 0
(-8325 4225);
DISPLAY 0.978723 (-8325 4225);
FORCEPROP 1 LAST VALUE 1K
J 0
(-8330 4425);
DISPLAY 0.978723 (-8330 4425);
FORCEPROP 1 LAST TOLERANCE 1%
J 0
(-8330 4375);
DISPLAY 0.978723 (-8330 4375);
FORCEPROP 1 LAST MATERIAL EMPTY
J 0
(-8335 4275);
DISPLAY 0.978723 (-8335 4275);
FORCEPROP 2 LAST CDS_LIB pure_quanta
J 0
(-8375 4350);
DISPLAY INVISIBLE (-8375 4350);
FORCEPROP 1 LAST PATH I120
J 0
(-8325 4525);
DISPLAY 0.978723 (-8325 4525);
PAINT WHITE (-8325 4525);
DISPLAY INVISIBLE (-8325 4525);
FORCEPROP 1 LAST PART_NUMBER CS21002FB06
J 0
(-8335 4225);
DISPLAY 0.978723 (-8335 4225);
DISPLAY INVISIBLE (-8335 4225);
FORCEADD Q_RES..2
(-8375 2075);
FORCEPROP 1 LAST LOCATION R6137
J 0
(-8330 2200);
DISPLAY 0.978723 (-8330 2200);
FORCEPROP 0 LAST $SEC 1
J 0
(-8325 2250);
DISPLAY 0.680851 (-8325 2250);
PAINT MONO (-8325 2250);
DISPLAY INVISIBLE (-8325 2250);
FORCEPROP 0 LAST CDS_SEC 1
J 0
(-8325 2250);
DISPLAY 0.680851 (-8325 2250);
DISPLAY INVISIBLE (-8325 2250);
FORCEPROP 1 LASTPIN (-8375 2175) $PN 1
J 0
(-8370 2137);
DISPLAY 0.787234 (-8370 2137);
PAINT MONO (-8370 2137);
FORCEPROP 1 LASTPIN (-8375 1975) $PN 2
J 0
(-8370 1985);
DISPLAY 0.787234 (-8370 1985);
PAINT MONO (-8370 1985);
FORCEPROP 1 LAST PACK_TYPE 0402LF
J 0
(-8325 1950);
DISPLAY 0.978723 (-8325 1950);
FORCEPROP 1 LAST MATERIAL EMPTY
J 0
(-8335 2000);
DISPLAY 0.978723 (-8335 2000);
FORCEPROP 1 LAST TOLERANCE 1%
J 0
(-8330 2100);
DISPLAY 0.978723 (-8330 2100);
FORCEPROP 1 LAST VALUE 1K
J 0
(-8330 2150);
DISPLAY 0.978723 (-8330 2150);
FORCEPROP 1 LAST WATTAGE 1/16W
J 0
(-8335 2050);
DISPLAY 0.978723 (-8335 2050);
FORCEPROP 2 LAST CDS_LIB pure_quanta
J 0
(-8375 2075);
DISPLAY INVISIBLE (-8375 2075);
FORCEPROP 1 LAST PATH I121
J 0
(-8325 2250);
DISPLAY 0.978723 (-8325 2250);
PAINT WHITE (-8325 2250);
DISPLAY INVISIBLE (-8325 2250);
FORCEPROP 1 LAST PART_NUMBER CS21002FB06
J 0
(-8335 1950);
DISPLAY 0.978723 (-8335 1950);
DISPLAY INVISIBLE (-8335 1950);
FORCEADD Q_RES..2
(-8375 1125);
FORCEPROP 1 LAST LOCATION R6142
J 0
(-8330 1250);
DISPLAY 0.978723 (-8330 1250);
FORCEPROP 0 LAST $SEC 1
J 0
(-8325 1300);
DISPLAY 0.680851 (-8325 1300);
PAINT MONO (-8325 1300);
DISPLAY INVISIBLE (-8325 1300);
FORCEPROP 0 LAST CDS_SEC 1
J 0
(-8325 1300);
DISPLAY 0.680851 (-8325 1300);
DISPLAY INVISIBLE (-8325 1300);
FORCEPROP 1 LASTPIN (-8375 1225) $PN 1
J 0
(-8370 1187);
DISPLAY 0.787234 (-8370 1187);
PAINT MONO (-8370 1187);
FORCEPROP 1 LASTPIN (-8375 1025) $PN 2
J 0
(-8370 1035);
DISPLAY 0.787234 (-8370 1035);
PAINT MONO (-8370 1035);
FORCEPROP 1 LAST PACK_TYPE 0402LF
J 0
(-8325 1000);
DISPLAY 0.978723 (-8325 1000);
FORCEPROP 1 LAST MATERIAL CHIP
J 0
(-8335 1050);
DISPLAY 0.978723 (-8335 1050);
FORCEPROP 1 LAST WATTAGE 1/16W
J 0
(-8335 1100);
DISPLAY 0.978723 (-8335 1100);
FORCEPROP 1 LAST TOLERANCE 1%
J 0
(-8330 1150);
DISPLAY 0.978723 (-8330 1150);
FORCEPROP 1 LAST VALUE 1K
J 0
(-8330 1200);
DISPLAY 0.978723 (-8330 1200);
FORCEPROP 2 LAST CDS_LIB pure_quanta
J 0
(-8375 1125);
DISPLAY INVISIBLE (-8375 1125);
FORCEPROP 1 LAST PATH I122
J 0
(-8325 1300);
DISPLAY 0.978723 (-8325 1300);
PAINT WHITE (-8325 1300);
DISPLAY INVISIBLE (-8325 1300);
FORCEPROP 1 LAST PART_NUMBER CS21002FB06
J 0
(-8335 1000);
DISPLAY 0.978723 (-8335 1000);
DISPLAY INVISIBLE (-8335 1000);
FORCEADD Q_RES..2
(-3650 4650);
FORCEPROP 1 LAST LOCATION R6130
J 0
(-3605 4775);
DISPLAY 0.978723 (-3605 4775);
FORCEPROP 0 LAST $SEC 1
J 0
(-3600 4825);
DISPLAY 0.680851 (-3600 4825);
PAINT MONO (-3600 4825);
DISPLAY INVISIBLE (-3600 4825);
FORCEPROP 0 LAST CDS_SEC 1
J 0
(-3600 4825);
DISPLAY 0.680851 (-3600 4825);
DISPLAY INVISIBLE (-3600 4825);
FORCEPROP 1 LASTPIN (-3650 4750) $PN 1
J 0
(-3645 4712);
DISPLAY 0.787234 (-3645 4712);
PAINT MONO (-3645 4712);
FORCEPROP 1 LASTPIN (-3650 4550) $PN 2
J 0
(-3645 4560);
DISPLAY 0.787234 (-3645 4560);
PAINT MONO (-3645 4560);
FORCEPROP 1 LAST PACK_TYPE 0402LF
J 0
(-3600 4525);
DISPLAY 0.978723 (-3600 4525);
FORCEPROP 1 LAST MATERIAL CHIP
J 0
(-3610 4575);
DISPLAY 0.978723 (-3610 4575);
FORCEPROP 1 LAST VALUE 1K
J 0
(-3605 4725);
DISPLAY 0.978723 (-3605 4725);
FORCEPROP 1 LAST WATTAGE 1/16W
J 0
(-3610 4625);
DISPLAY 0.978723 (-3610 4625);
FORCEPROP 1 LAST TOLERANCE 1%
J 0
(-3605 4675);
DISPLAY 0.978723 (-3605 4675);
FORCEPROP 2 LAST CDS_LIB pure_quanta
J 0
(-3650 4650);
DISPLAY INVISIBLE (-3650 4650);
FORCEPROP 1 LAST PATH I131
J 0
(-3600 4825);
DISPLAY 0.978723 (-3600 4825);
PAINT WHITE (-3600 4825);
DISPLAY INVISIBLE (-3600 4825);
FORCEPROP 1 LAST PART_NUMBER CS21002FB06
J 0
(-3610 4525);
DISPLAY 0.978723 (-3610 4525);
DISPLAY INVISIBLE (-3610 4525);
FORCEADD Q_RES..2
(-3650 3700);
FORCEPROP 1 LAST LOCATION R6133
J 0
(-3605 3825);
DISPLAY 0.978723 (-3605 3825);
FORCEPROP 0 LAST $SEC 1
J 0
(-3600 3875);
DISPLAY 0.680851 (-3600 3875);
PAINT MONO (-3600 3875);
DISPLAY INVISIBLE (-3600 3875);
FORCEPROP 0 LAST CDS_SEC 1
J 0
(-3600 3875);
DISPLAY 0.680851 (-3600 3875);
DISPLAY INVISIBLE (-3600 3875);
FORCEPROP 1 LASTPIN (-3650 3800) $PN 1
J 0
(-3645 3762);
DISPLAY 0.787234 (-3645 3762);
PAINT MONO (-3645 3762);
FORCEPROP 1 LASTPIN (-3650 3600) $PN 2
J 0
(-3645 3610);
DISPLAY 0.787234 (-3645 3610);
PAINT MONO (-3645 3610);
FORCEPROP 1 LAST PACK_TYPE 0402LF
J 0
(-3600 3575);
DISPLAY 0.978723 (-3600 3575);
FORCEPROP 1 LAST MATERIAL EMPTY
J 0
(-3610 3625);
DISPLAY 0.978723 (-3610 3625);
FORCEPROP 1 LAST WATTAGE 1/16W
J 0
(-3610 3675);
DISPLAY 0.978723 (-3610 3675);
FORCEPROP 1 LAST VALUE 1K
J 0
(-3605 3775);
DISPLAY 0.978723 (-3605 3775);
FORCEPROP 1 LAST TOLERANCE 1%
J 0
(-3605 3725);
DISPLAY 0.978723 (-3605 3725);
FORCEPROP 2 LAST CDS_LIB pure_quanta
J 0
(-3650 3700);
DISPLAY INVISIBLE (-3650 3700);
FORCEPROP 1 LAST PATH I132
J 0
(-3600 3875);
DISPLAY 0.978723 (-3600 3875);
PAINT WHITE (-3600 3875);
DISPLAY INVISIBLE (-3600 3875);
FORCEPROP 1 LAST PART_NUMBER CS21002FB06
J 0
(-3610 3575);
DISPLAY 0.978723 (-3610 3575);
DISPLAY INVISIBLE (-3610 3575);
FORCEADD Q_RES..2
(-3300 3700);
FORCEPROP 1 LAST LOCATION R6134
J 0
(-3255 3825);
DISPLAY 0.978723 (-3255 3825);
FORCEPROP 0 LAST $SEC 1
J 0
(-3250 3875);
DISPLAY 0.680851 (-3250 3875);
PAINT MONO (-3250 3875);
DISPLAY INVISIBLE (-3250 3875);
FORCEPROP 0 LAST CDS_SEC 1
J 0
(-3250 3875);
DISPLAY 0.680851 (-3250 3875);
DISPLAY INVISIBLE (-3250 3875);
FORCEPROP 1 LASTPIN (-3300 3800) $PN 1
J 0
(-3295 3762);
DISPLAY 0.787234 (-3295 3762);
PAINT MONO (-3295 3762);
FORCEPROP 1 LASTPIN (-3300 3600) $PN 2
J 0
(-3295 3610);
DISPLAY 0.787234 (-3295 3610);
PAINT MONO (-3295 3610);
FORCEPROP 1 LAST PACK_TYPE 0402LF
J 0
(-3250 3575);
DISPLAY 0.978723 (-3250 3575);
FORCEPROP 1 LAST MATERIAL CHIP
J 0
(-3260 3625);
DISPLAY 0.978723 (-3260 3625);
FORCEPROP 1 LAST WATTAGE 1/16W
J 0
(-3260 3675);
DISPLAY 0.978723 (-3260 3675);
FORCEPROP 1 LAST TOLERANCE 1%
J 0
(-3255 3725);
DISPLAY 0.978723 (-3255 3725);
FORCEPROP 1 LAST VALUE 1K
J 0
(-3255 3775);
DISPLAY 0.978723 (-3255 3775);
FORCEPROP 2 LAST CDS_LIB pure_quanta
J 0
(-3300 3700);
DISPLAY INVISIBLE (-3300 3700);
FORCEPROP 1 LAST PATH I133
J 0
(-3250 3875);
DISPLAY 0.978723 (-3250 3875);
PAINT WHITE (-3250 3875);
DISPLAY INVISIBLE (-3250 3875);
FORCEPROP 1 LAST PART_NUMBER CS21002FB06
J 0
(-3260 3575);
DISPLAY 0.978723 (-3260 3575);
DISPLAY INVISIBLE (-3260 3575);
FORCEADD Q_RES..2
(-3300 4650);
FORCEPROP 1 LAST LOCATION R6131
J 0
(-3255 4775);
DISPLAY 0.978723 (-3255 4775);
FORCEPROP 0 LAST $SEC 1
J 0
(-3250 4825);
DISPLAY 0.680851 (-3250 4825);
PAINT MONO (-3250 4825);
DISPLAY INVISIBLE (-3250 4825);
FORCEPROP 0 LAST CDS_SEC 1
J 0
(-3250 4825);
DISPLAY 0.680851 (-3250 4825);
DISPLAY INVISIBLE (-3250 4825);
FORCEPROP 1 LASTPIN (-3300 4750) $PN 1
J 0
(-3295 4712);
DISPLAY 0.787234 (-3295 4712);
PAINT MONO (-3295 4712);
FORCEPROP 1 LASTPIN (-3300 4550) $PN 2
J 0
(-3295 4560);
DISPLAY 0.787234 (-3295 4560);
PAINT MONO (-3295 4560);
FORCEPROP 1 LAST VALUE 1K
J 0
(-3255 4725);
DISPLAY 0.978723 (-3255 4725);
FORCEPROP 1 LAST TOLERANCE 1%
J 0
(-3255 4675);
DISPLAY 0.978723 (-3255 4675);
FORCEPROP 1 LAST MATERIAL EMPTY
J 0
(-3260 4575);
DISPLAY 0.978723 (-3260 4575);
FORCEPROP 1 LAST WATTAGE 1/16W
J 0
(-3260 4625);
DISPLAY 0.978723 (-3260 4625);
FORCEPROP 1 LAST PACK_TYPE 0402LF
J 0
(-3250 4525);
DISPLAY 0.978723 (-3250 4525);
FORCEPROP 2 LAST CDS_LIB pure_quanta
J 0
(-3300 4650);
DISPLAY INVISIBLE (-3300 4650);
FORCEPROP 1 LAST PATH I134
J 0
(-3250 4825);
DISPLAY 0.978723 (-3250 4825);
PAINT WHITE (-3250 4825);
DISPLAY INVISIBLE (-3250 4825);
FORCEPROP 1 LAST PART_NUMBER CS21002FB06
J 0
(-3260 4525);
DISPLAY 0.978723 (-3260 4525);
DISPLAY INVISIBLE (-3260 4525);
FORCEADD Q_RES..2
(-2950 4650);
FORCEPROP 1 LAST LOCATION R6132
J 0
(-2905 4775);
DISPLAY 0.978723 (-2905 4775);
FORCEPROP 0 LAST $SEC 1
J 0
(-2900 4825);
DISPLAY 0.680851 (-2900 4825);
PAINT MONO (-2900 4825);
DISPLAY INVISIBLE (-2900 4825);
FORCEPROP 0 LAST CDS_SEC 1
J 0
(-2900 4825);
DISPLAY 0.680851 (-2900 4825);
DISPLAY INVISIBLE (-2900 4825);
FORCEPROP 1 LASTPIN (-2950 4750) $PN 1
J 0
(-2945 4712);
DISPLAY 0.787234 (-2945 4712);
PAINT MONO (-2945 4712);
FORCEPROP 1 LASTPIN (-2950 4550) $PN 2
J 0
(-2945 4560);
DISPLAY 0.787234 (-2945 4560);
PAINT MONO (-2945 4560);
FORCEPROP 1 LAST PACK_TYPE 0402LF
J 0
(-2910 4475);
DISPLAY 0.978723 (-2910 4475);
FORCEPROP 1 LAST TOLERANCE 1%
J 0
(-2905 4675);
DISPLAY 0.978723 (-2905 4675);
FORCEPROP 1 LAST VALUE 1K
J 0
(-2905 4725);
DISPLAY 0.978723 (-2905 4725);
FORCEPROP 1 LAST MATERIAL EMPTY
J 0
(-2910 4575);
DISPLAY 0.978723 (-2910 4575);
FORCEPROP 1 LAST WATTAGE 1/16W
J 0
(-2910 4625);
DISPLAY 0.978723 (-2910 4625);
FORCEPROP 2 LAST CDS_LIB pure_quanta
J 0
(-2950 4650);
DISPLAY INVISIBLE (-2950 4650);
FORCEPROP 1 LAST PATH I135
J 0
(-2900 4825);
DISPLAY 0.978723 (-2900 4825);
PAINT WHITE (-2900 4825);
DISPLAY INVISIBLE (-2900 4825);
FORCEPROP 1 LAST PART_NUMBER CS21002FB06
J 0
(-2910 4525);
DISPLAY 0.978723 (-2910 4525);
DISPLAY INVISIBLE (-2910 4525);
FORCEADD Q_RES..2
(-2950 3700);
FORCEPROP 1 LAST LOCATION R6135
J 0
(-2905 3825);
DISPLAY 0.978723 (-2905 3825);
FORCEPROP 0 LAST $SEC 1
J 0
(-2900 3875);
DISPLAY 0.680851 (-2900 3875);
PAINT MONO (-2900 3875);
DISPLAY INVISIBLE (-2900 3875);
FORCEPROP 0 LAST CDS_SEC 1
J 0
(-2900 3875);
DISPLAY 0.680851 (-2900 3875);
DISPLAY INVISIBLE (-2900 3875);
FORCEPROP 1 LASTPIN (-2950 3800) $PN 1
J 0
(-2945 3762);
DISPLAY 0.787234 (-2945 3762);
PAINT MONO (-2945 3762);
FORCEPROP 1 LASTPIN (-2950 3600) $PN 2
J 0
(-2945 3610);
DISPLAY 0.787234 (-2945 3610);
PAINT MONO (-2945 3610);
FORCEPROP 1 LAST VALUE 1K
J 0
(-2905 3775);
DISPLAY 0.978723 (-2905 3775);
FORCEPROP 1 LAST TOLERANCE 1%
J 0
(-2905 3725);
DISPLAY 0.978723 (-2905 3725);
FORCEPROP 1 LAST WATTAGE 1/16W
J 0
(-2910 3675);
DISPLAY 0.978723 (-2910 3675);
FORCEPROP 1 LAST MATERIAL CHIP
J 0
(-2910 3625);
DISPLAY 0.978723 (-2910 3625);
FORCEPROP 1 LAST PACK_TYPE 0402LF
J 0
(-2910 3525);
DISPLAY 0.978723 (-2910 3525);
FORCEPROP 2 LAST CDS_LIB pure_quanta
J 0
(-2950 3700);
DISPLAY INVISIBLE (-2950 3700);
FORCEPROP 1 LAST PATH I136
J 0
(-2900 3875);
DISPLAY 0.978723 (-2900 3875);
PAINT WHITE (-2900 3875);
DISPLAY INVISIBLE (-2900 3875);
FORCEPROP 1 LAST PART_NUMBER CS21002FB06
J 0
(-2910 3575);
DISPLAY 0.978723 (-2910 3575);
DISPLAY INVISIBLE (-2910 3575);
FORCEADD Q_RES..2
(-3650 1050);
FORCEPROP 1 LAST LOCATION R6149
J 0
(-3605 1175);
DISPLAY 0.978723 (-3605 1175);
FORCEPROP 0 LAST $SEC 1
J 0
(-3600 1225);
DISPLAY 0.680851 (-3600 1225);
PAINT MONO (-3600 1225);
DISPLAY INVISIBLE (-3600 1225);
FORCEPROP 0 LAST CDS_SEC 1
J 0
(-3600 1225);
DISPLAY 0.680851 (-3600 1225);
DISPLAY INVISIBLE (-3600 1225);
FORCEPROP 1 LASTPIN (-3650 1150) $PN 1
J 0
(-3645 1112);
DISPLAY 0.787234 (-3645 1112);
PAINT MONO (-3645 1112);
FORCEPROP 1 LASTPIN (-3650 950) $PN 2
J 0
(-3645 960);
DISPLAY 0.787234 (-3645 960);
PAINT MONO (-3645 960);
FORCEPROP 1 LAST WATTAGE 1/16W
J 0
(-3610 1025);
DISPLAY 0.978723 (-3610 1025);
FORCEPROP 1 LAST MATERIAL EMPTY
J 0
(-3610 975);
DISPLAY 0.978723 (-3610 975);
FORCEPROP 1 LAST PACK_TYPE 0402LF
J 0
(-3600 925);
DISPLAY 0.978723 (-3600 925);
FORCEPROP 1 LAST TOLERANCE 1%
J 0
(-3605 1075);
DISPLAY 0.978723 (-3605 1075);
FORCEPROP 1 LAST VALUE 1K
J 0
(-3605 1125);
DISPLAY 0.978723 (-3605 1125);
FORCEPROP 2 LAST CDS_LIB pure_quanta
J 0
(-3650 1050);
DISPLAY INVISIBLE (-3650 1050);
FORCEPROP 1 LAST PATH I137
J 0
(-3600 1225);
DISPLAY 0.978723 (-3600 1225);
PAINT WHITE (-3600 1225);
DISPLAY INVISIBLE (-3600 1225);
FORCEPROP 1 LAST PART_NUMBER CS21002FB06
J 0
(-3610 925);
DISPLAY 0.978723 (-3610 925);
DISPLAY INVISIBLE (-3610 925);
FORCEADD Q_RES..2
(-3650 2000);
FORCEPROP 1 LAST LOCATION R6146
J 0
(-3605 2125);
DISPLAY 0.978723 (-3605 2125);
FORCEPROP 0 LAST $SEC 1
J 0
(-3600 2175);
DISPLAY 0.680851 (-3600 2175);
PAINT MONO (-3600 2175);
DISPLAY INVISIBLE (-3600 2175);
FORCEPROP 0 LAST CDS_SEC 1
J 0
(-3600 2175);
DISPLAY 0.680851 (-3600 2175);
DISPLAY INVISIBLE (-3600 2175);
FORCEPROP 1 LASTPIN (-3650 2100) $PN 1
J 0
(-3645 2062);
DISPLAY 0.787234 (-3645 2062);
PAINT MONO (-3645 2062);
FORCEPROP 1 LASTPIN (-3650 1900) $PN 2
J 0
(-3645 1910);
DISPLAY 0.787234 (-3645 1910);
PAINT MONO (-3645 1910);
FORCEPROP 1 LAST TOLERANCE 1%
J 0
(-3605 2025);
DISPLAY 0.978723 (-3605 2025);
FORCEPROP 1 LAST VALUE 1K
J 0
(-3605 2075);
DISPLAY 0.978723 (-3605 2075);
FORCEPROP 1 LAST WATTAGE 1/16W
J 0
(-3610 1975);
DISPLAY 0.978723 (-3610 1975);
FORCEPROP 1 LAST MATERIAL CHIP
J 0
(-3610 1925);
DISPLAY 0.978723 (-3610 1925);
FORCEPROP 1 LAST PACK_TYPE 0402LF
J 0
(-3600 1875);
DISPLAY 0.978723 (-3600 1875);
FORCEPROP 2 LAST CDS_LIB pure_quanta
J 0
(-3650 2000);
DISPLAY INVISIBLE (-3650 2000);
FORCEPROP 1 LAST PATH I138
J 0
(-3600 2175);
DISPLAY 0.978723 (-3600 2175);
PAINT WHITE (-3600 2175);
DISPLAY INVISIBLE (-3600 2175);
FORCEPROP 1 LAST PART_NUMBER CS21002FB06
J 0
(-3610 1875);
DISPLAY 0.978723 (-3610 1875);
DISPLAY INVISIBLE (-3610 1875);
FORCEADD Q_RES..2
(-3300 1050);
FORCEPROP 1 LAST LOCATION R6150
J 0
(-3255 1175);
DISPLAY 0.978723 (-3255 1175);
FORCEPROP 0 LAST $SEC 1
J 0
(-3250 1225);
DISPLAY 0.680851 (-3250 1225);
PAINT MONO (-3250 1225);
DISPLAY INVISIBLE (-3250 1225);
FORCEPROP 0 LAST CDS_SEC 1
J 0
(-3250 1225);
DISPLAY 0.680851 (-3250 1225);
DISPLAY INVISIBLE (-3250 1225);
FORCEPROP 1 LASTPIN (-3300 1150) $PN 1
J 0
(-3295 1112);
DISPLAY 0.787234 (-3295 1112);
PAINT MONO (-3295 1112);
FORCEPROP 1 LASTPIN (-3300 950) $PN 2
J 0
(-3295 960);
DISPLAY 0.787234 (-3295 960);
PAINT MONO (-3295 960);
FORCEPROP 1 LAST WATTAGE 1/16W
J 0
(-3260 1025);
DISPLAY 0.978723 (-3260 1025);
FORCEPROP 1 LAST PACK_TYPE 0402LF
J 0
(-3250 925);
DISPLAY 0.978723 (-3250 925);
FORCEPROP 1 LAST TOLERANCE 1%
J 0
(-3255 1075);
DISPLAY 0.978723 (-3255 1075);
FORCEPROP 1 LAST MATERIAL CHIP
J 0
(-3260 975);
DISPLAY 0.978723 (-3260 975);
FORCEPROP 1 LAST VALUE 1K
J 0
(-3255 1125);
DISPLAY 0.978723 (-3255 1125);
FORCEPROP 2 LAST CDS_LIB pure_quanta
J 0
(-3300 1050);
DISPLAY INVISIBLE (-3300 1050);
FORCEPROP 1 LAST PATH I139
J 0
(-3250 1225);
DISPLAY 0.978723 (-3250 1225);
PAINT WHITE (-3250 1225);
DISPLAY INVISIBLE (-3250 1225);
FORCEPROP 1 LAST PART_NUMBER CS21002FB06
J 0
(-3260 925);
DISPLAY 0.978723 (-3260 925);
DISPLAY INVISIBLE (-3260 925);
FORCEADD Q_RES..2
(-3300 2000);
FORCEPROP 1 LAST LOCATION R6147
J 0
(-3255 2125);
DISPLAY 0.978723 (-3255 2125);
FORCEPROP 0 LAST $SEC 1
J 0
(-3250 2175);
DISPLAY 0.680851 (-3250 2175);
PAINT MONO (-3250 2175);
DISPLAY INVISIBLE (-3250 2175);
FORCEPROP 0 LAST CDS_SEC 1
J 0
(-3250 2175);
DISPLAY 0.680851 (-3250 2175);
DISPLAY INVISIBLE (-3250 2175);
FORCEPROP 1 LASTPIN (-3300 2100) $PN 1
J 0
(-3295 2062);
DISPLAY 0.787234 (-3295 2062);
PAINT MONO (-3295 2062);
FORCEPROP 1 LASTPIN (-3300 1900) $PN 2
J 0
(-3295 1910);
DISPLAY 0.787234 (-3295 1910);
PAINT MONO (-3295 1910);
FORCEPROP 1 LAST TOLERANCE 1%
J 0
(-3255 2025);
DISPLAY 0.978723 (-3255 2025);
FORCEPROP 1 LAST VALUE 1K
J 0
(-3255 2075);
DISPLAY 0.978723 (-3255 2075);
FORCEPROP 1 LAST MATERIAL EMPTY
J 0
(-3260 1925);
DISPLAY 0.978723 (-3260 1925);
FORCEPROP 1 LAST WATTAGE 1/16W
J 0
(-3260 1975);
DISPLAY 0.978723 (-3260 1975);
FORCEPROP 1 LAST PACK_TYPE 0402LF
J 0
(-3250 1875);
DISPLAY 0.978723 (-3250 1875);
FORCEPROP 2 LAST CDS_LIB pure_quanta
J 0
(-3300 2000);
DISPLAY INVISIBLE (-3300 2000);
FORCEPROP 1 LAST PATH I140
J 0
(-3250 2175);
DISPLAY 0.978723 (-3250 2175);
PAINT WHITE (-3250 2175);
DISPLAY INVISIBLE (-3250 2175);
FORCEPROP 1 LAST PART_NUMBER CS21002FB06
J 0
(-3260 1875);
DISPLAY 0.978723 (-3260 1875);
DISPLAY INVISIBLE (-3260 1875);
FORCEADD Q_RES..2
(-2950 1050);
FORCEPROP 1 LAST LOCATION R6151
J 0
(-2905 1175);
DISPLAY 0.978723 (-2905 1175);
FORCEPROP 0 LAST $SEC 1
J 0
(-2900 1225);
DISPLAY 0.680851 (-2900 1225);
PAINT MONO (-2900 1225);
DISPLAY INVISIBLE (-2900 1225);
FORCEPROP 0 LAST CDS_SEC 1
J 0
(-2900 1225);
DISPLAY 0.680851 (-2900 1225);
DISPLAY INVISIBLE (-2900 1225);
FORCEPROP 1 LASTPIN (-2950 1150) $PN 1
J 0
(-2945 1112);
DISPLAY 0.787234 (-2945 1112);
PAINT MONO (-2945 1112);
FORCEPROP 1 LASTPIN (-2950 950) $PN 2
J 0
(-2945 960);
DISPLAY 0.787234 (-2945 960);
PAINT MONO (-2945 960);
FORCEPROP 1 LAST WATTAGE 1/16W
J 0
(-2910 1025);
DISPLAY 0.978723 (-2910 1025);
FORCEPROP 1 LAST MATERIAL CHIP
J 0
(-2910 975);
DISPLAY 0.978723 (-2910 975);
FORCEPROP 1 LAST TOLERANCE 1%
J 0
(-2905 1075);
DISPLAY 0.978723 (-2905 1075);
FORCEPROP 1 LAST PACK_TYPE 0402LF
J 0
(-2910 875);
DISPLAY 0.978723 (-2910 875);
FORCEPROP 1 LAST VALUE 1K
J 0
(-2905 1125);
DISPLAY 0.978723 (-2905 1125);
FORCEPROP 2 LAST CDS_LIB pure_quanta
J 0
(-2950 1050);
DISPLAY INVISIBLE (-2950 1050);
FORCEPROP 1 LAST PATH I141
J 0
(-2900 1225);
DISPLAY 0.978723 (-2900 1225);
PAINT WHITE (-2900 1225);
DISPLAY INVISIBLE (-2900 1225);
FORCEPROP 1 LAST PART_NUMBER CS21002FB06
J 0
(-2910 925);
DISPLAY 0.978723 (-2910 925);
DISPLAY INVISIBLE (-2910 925);
FORCEADD Q_RES..2
(-2950 2000);
FORCEPROP 1 LAST LOCATION R6148
J 0
(-2905 2125);
DISPLAY 0.978723 (-2905 2125);
FORCEPROP 0 LAST $SEC 1
J 0
(-2900 2175);
DISPLAY 0.680851 (-2900 2175);
PAINT MONO (-2900 2175);
DISPLAY INVISIBLE (-2900 2175);
FORCEPROP 0 LAST CDS_SEC 1
J 0
(-2900 2175);
DISPLAY 0.680851 (-2900 2175);
DISPLAY INVISIBLE (-2900 2175);
FORCEPROP 1 LASTPIN (-2950 2100) $PN 1
J 0
(-2945 2062);
DISPLAY 0.787234 (-2945 2062);
PAINT MONO (-2945 2062);
FORCEPROP 1 LASTPIN (-2950 1900) $PN 2
J 0
(-2945 1910);
DISPLAY 0.787234 (-2945 1910);
PAINT MONO (-2945 1910);
FORCEPROP 1 LAST TOLERANCE 1%
J 0
(-2905 2025);
DISPLAY 0.978723 (-2905 2025);
FORCEPROP 1 LAST MATERIAL EMPTY
J 0
(-2910 1925);
DISPLAY 0.978723 (-2910 1925);
FORCEPROP 1 LAST PACK_TYPE 0402LF
J 0
(-2910 1825);
DISPLAY 0.978723 (-2910 1825);
FORCEPROP 1 LAST WATTAGE 1/16W
J 0
(-2910 1975);
DISPLAY 0.978723 (-2910 1975);
FORCEPROP 1 LAST VALUE 1K
J 0
(-2905 2075);
DISPLAY 0.978723 (-2905 2075);
FORCEPROP 2 LAST CDS_LIB pure_quanta
J 0
(-2950 2000);
DISPLAY INVISIBLE (-2950 2000);
FORCEPROP 1 LAST PATH I142
J 0
(-2900 2175);
DISPLAY 0.978723 (-2900 2175);
PAINT WHITE (-2900 2175);
DISPLAY INVISIBLE (-2900 2175);
FORCEPROP 1 LAST PART_NUMBER CS21002FB06
J 0
(-2910 1875);
DISPLAY 0.978723 (-2910 1875);
DISPLAY INVISIBLE (-2910 1875);
FORCEADD OFFPAGE..1
(-3750 5525);
FORCEPROP 2 LAST $XR0 81 
J 0
(-4001 5525);
DISPLAY 0.638298 (-4001 5525);
PAINT MONO (-4001 5525);
FORCEPROP 2 LAST CDS_LIB standard
J 0
(-3750 5525);
DISPLAY INVISIBLE (-3750 5525);
FORCEPROP 1 LAST OFFPAGE TRUE
J 0
(-3425 5400);
DISPLAY 0.872340 (-3425 5400);
PAINT GREEN (-3425 5400);
DISPLAY INVISIBLE (-3425 5400);
FORCEPROP 1 LAST COMMENT_BODY TRUE
J 0
(-3625 5425);
DISPLAY 0.872340 (-3625 5425);
PAINT GREEN (-3625 5425);
DISPLAY INVISIBLE (-3625 5425);
FORCEPROP 2 LAST PATH I2
J 0
(-3950 5575);
DISPLAY 0.680851 (-3950 5575);
DISPLAY INVISIBLE (-3950 5575);
FORCEADD Q_RES..2
R 2
(-2975 5850);
FORCEPROP 1 LAST LOCATION R996
J 2
(-3020 5975);
DISPLAY 0.489362 (-3020 5975);
PAINT SKYBLUE (-3020 5975);
FORCEPROP 0 LAST $SEC 1
J 0
(-3000 6025);
DISPLAY 0.680851 (-3000 6025);
PAINT MONO (-3000 6025);
DISPLAY INVISIBLE (-3000 6025);
FORCEPROP 0 LAST CDS_SEC 1
J 0
(-3000 6025);
DISPLAY 0.680851 (-3000 6025);
DISPLAY INVISIBLE (-3000 6025);
FORCEPROP 1 LASTPIN (-2975 5950) $PN 1
J 2
(-2980 5912);
DISPLAY 0.489362 (-2980 5912);
PAINT MONO (-2980 5912);
FORCEPROP 1 LASTPIN (-2975 5750) $PN 2
J 2
(-2980 5760);
DISPLAY 0.489362 (-2980 5760);
PAINT MONO (-2980 5760);
FORCEPROP 1 LAST PACK_TYPE 0402LF
J 2
(-3015 5675);
DISPLAY 0.489362 (-3015 5675);
PAINT SKYBLUE (-3015 5675);
FORCEPROP 1 LAST TOLERANCE 5%
J 2
(-3020 5875);
DISPLAY 0.489362 (-3020 5875);
PAINT SKYBLUE (-3020 5875);
FORCEPROP 1 LAST MATERIAL CHIP
J 2
(-3015 5775);
DISPLAY 0.489362 (-3015 5775);
PAINT SKYBLUE (-3015 5775);
FORCEPROP 1 LAST WATTAGE 1/16W
J 2
(-3015 5825);
DISPLAY 0.489362 (-3015 5825);
PAINT SKYBLUE (-3015 5825);
FORCEPROP 1 LAST VALUE 4.7K
J 2
(-3020 5925);
DISPLAY 0.489362 (-3020 5925);
PAINT SKYBLUE (-3020 5925);
FORCEPROP 2 LAST BOM_COST OCP3.0 
J 2
(-3025 6025);
DISPLAY 0.680851 (-3025 6025);
DISPLAY INVISIBLE (-3025 6025);
FORCEPROP 2 LAST CDS_LIB pure_quanta
J 2
(-2975 5850);
DISPLAY INVISIBLE (-2975 5850);
FORCEPROP 1 LAST PATH I22
J 2
(-3025 6025);
DISPLAY 0.978723 (-3025 6025);
PAINT WHITE (-3025 6025);
DISPLAY INVISIBLE (-3025 6025);
FORCEPROP 1 LAST PART_NUMBER CS24702JB10
J 2
(-3015 5725);
DISPLAY 0.489362 (-3015 5725);
PAINT SKYBLUE (-3015 5725);
DISPLAY INVISIBLE (-3015 5725);
FORCEADD UNIVERSAL_GND..1
(-2850 5650);
FORCEPROP 3 LASTPIN (-2850 5700) SIG_NAME GND\g
J 0
(-2840 5710);
DISPLAY 0.659574 (-2840 5710);
PAINT MONO (-2840 5710);
DISPLAY INVISIBLE (-2840 5710);
FORCEPROP 2 LAST CDS_LIB pure_quanta_power
J 0
(-2850 5650);
DISPLAY INVISIBLE (-2850 5650);
FORCEPROP 2 LAST BOM_COST OCP3.0 
J 0
(-3050 5725);
DISPLAY 0.680851 (-3050 5725);
DISPLAY INVISIBLE (-3050 5725);
FORCEPROP 1 LAST HDL_POWER GND
J 1
(-2825 5575);
DISPLAY 0.872340 (-2825 5575);
PAINT GREEN (-2825 5575);
DISPLAY INVISIBLE (-2825 5575);
FORCEPROP 1 LAST PATH I23
J 0
(-2775 5650);
DISPLAY 0.872340 (-2775 5650);
PAINT AQUA (-2775 5650);
DISPLAY INVISIBLE (-2775 5650);
FORCEADD Q_CAP..1
(-2850 5850);
FORCEPROP 1 LAST LOCATION C552
J 0
(-2800 5950);
DISPLAY 0.489362 (-2800 5950);
PAINT SKYBLUE (-2800 5950);
FORCEPROP 0 LAST $SEC 1
J 0
(-2800 6000);
DISPLAY 0.680851 (-2800 6000);
PAINT MONO (-2800 6000);
DISPLAY INVISIBLE (-2800 6000);
FORCEPROP 0 LAST CDS_SEC 1
J 0
(-2800 6000);
DISPLAY 0.680851 (-2800 6000);
DISPLAY INVISIBLE (-2800 6000);
FORCEPROP 1 LASTPIN (-2850 5950) $PN 1
J 0
(-2840 5930);
DISPLAY 0.489362 (-2840 5930);
PAINT MONO (-2840 5930);
FORCEPROP 1 LASTPIN (-2850 5750) $PN 2
J 0
(-2840 5730);
DISPLAY 0.489362 (-2840 5730);
PAINT MONO (-2840 5730);
FORCEPROP 1 LAST PACK_TYPE 0402
J 0
(-2775 5675);
DISPLAY 0.489362 (-2775 5675);
PAINT SKYBLUE (-2775 5675);
FORCEPROP 1 LAST VALUE 0.1UF
J 0
(-2775 5925);
DISPLAY 0.489362 (-2775 5925);
PAINT SKYBLUE (-2775 5925);
FORCEPROP 1 LAST MATERIAL X7R
J 0
(-2775 5775);
DISPLAY 0.489362 (-2775 5775);
PAINT SKYBLUE (-2775 5775);
FORCEPROP 1 LAST TOLERANCE 10%
J 0
(-2775 5825);
DISPLAY 0.489362 (-2775 5825);
PAINT SKYBLUE (-2775 5825);
FORCEPROP 1 LAST VOLTAGE 25V
J 0
(-2775 5875);
DISPLAY 0.489362 (-2775 5875);
PAINT SKYBLUE (-2775 5875);
FORCEPROP 2 LAST CDS_LIB pure_quanta
J 0
(-2850 5850);
DISPLAY INVISIBLE (-2850 5850);
FORCEPROP 2 LAST BOM_COST OCP3.0 
J 0
(-2825 5975);
DISPLAY 0.680851 (-2825 5975);
DISPLAY INVISIBLE (-2825 5975);
FORCEPROP 1 LAST PATH I24
J 0
(-2800 6000);
DISPLAY 0.978723 (-2800 6000);
PAINT WHITE (-2800 6000);
DISPLAY INVISIBLE (-2800 6000);
FORCEPROP 1 LAST PART_NUMBER CH4104K1B00
J 0
(-2775 5725);
DISPLAY 0.489362 (-2775 5725);
PAINT SKYBLUE (-2775 5725);
DISPLAY INVISIBLE (-2775 5725);
FORCEADD UNIVERSAL_POWER..1
(-2850 6150);
FORCEPROP 3 LASTPIN (-2850 6100) SIG_NAME P1V8_AUX\g
J 0
(-2840 6110);
DISPLAY 0.659574 (-2840 6110);
PAINT MONO (-2840 6110);
DISPLAY INVISIBLE (-2840 6110);
FORCEPROP 1 LAST HDL_POWER P1V8_AUX
J 1
(-2850 6200);
DISPLAY 0.489362 (-2850 6200);
PAINT GREEN (-2850 6200);
FORCEPROP 2 LAST CDS_LIB pure_quanta_power
J 0
(-2850 6150);
DISPLAY INVISIBLE (-2850 6150);
FORCEPROP 2 LAST BOM_COST OCP3.0 
J 0
(-2850 6250);
DISPLAY 0.680851 (-2850 6250);
DISPLAY INVISIBLE (-2850 6250);
FORCEPROP 1 LAST PATH I25
J 0
(-2800 6175);
DISPLAY 0.872340 (-2800 6175);
PAINT AQUA (-2800 6175);
DISPLAY INVISIBLE (-2800 6175);
FORCEADD SN74LVC1G07DBVR..1
(-2250 5525);
FORCEPROP 1 LAST LOCATION U92
J 0
(-2375 5780);
DISPLAY 0.489362 (-2375 5780);
PAINT SKYBLUE (-2375 5780);
FORCEPROP 0 LAST $SEC 1
J 0
(-2375 5925);
DISPLAY 0.680851 (-2375 5925);
PAINT MONO (-2375 5925);
DISPLAY INVISIBLE (-2375 5925);
FORCEPROP 0 LAST CDS_SEC 1
J 0
(-2375 5925);
DISPLAY 0.680851 (-2375 5925);
DISPLAY INVISIBLE (-2375 5925);
FORCEPROP 0 LASTPIN (-2425 5525) $PN 2
J 2
(-2435 5535);
DISPLAY 0.489362 (-2435 5535);
PAINT MONO (-2435 5535);
FORCEPROP 0 LASTPIN (-2425 5425) $PN 3
J 2
(-2435 5435);
DISPLAY 0.489362 (-2435 5435);
PAINT MONO (-2435 5435);
FORCEPROP 0 LASTPIN (-2075 5425) $PN 1
J 0
(-2065 5435);
DISPLAY 0.489362 (-2065 5435);
PAINT MONO (-2065 5435);
FORCEPROP 0 LASTPIN (-2425 5625) $PN 5
J 2
(-2435 5635);
DISPLAY 0.489362 (-2435 5635);
PAINT MONO (-2435 5635);
FORCEPROP 0 LASTPIN (-2075 5525) $PN 4
J 0
(-2065 5535);
DISPLAY 0.489362 (-2065 5535);
PAINT MONO (-2065 5535);
FORCEPROP 2 LAST PACK_TYPE SMLF
J 0
(-2375 5825);
DISPLAY 0.489362 (-2375 5825);
PAINT SKYBLUE (-2375 5825);
FORCEPROP 2 LAST VALUE SN74LVC1G07DBVR
J 0
(-2375 5875);
DISPLAY 0.489362 (-2375 5875);
PAINT SKYBLUE (-2375 5875);
FORCEPROP 1 LAST MATERIAL IC
J 0
(-2375 5685);
DISPLAY 0.489362 (-2375 5685);
PAINT SKYBLUE (-2375 5685);
FORCEPROP 2 LAST CDS_LIB pure_quanta
J 0
(-2250 5525);
DISPLAY INVISIBLE (-2250 5525);
FORCEPROP 1 LAST NEEDS_NO_SIZE TRUE
J 0
(-2250 5525);
DISPLAY 0.468085 (-2250 5525);
PAINT GREEN (-2250 5525);
DISPLAY INVISIBLE (-2250 5525);
FORCEPROP 1 LAST PATH I26
J 0
(-2150 5680);
DISPLAY 0.723404 (-2150 5680);
PAINT GREEN (-2150 5680);
DISPLAY INVISIBLE (-2150 5680);
FORCEPROP 1 LAST PART_NUMBER AL1G0007024
J 0
(-2375 5735);
DISPLAY 0.489362 (-2375 5735);
PAINT SKYBLUE (-2375 5735);
DISPLAY INVISIBLE (-2375 5735);
FORCEADD Q_RES..1
(-1500 5525);
FORCEPROP 1 LAST LOCATION R71
J 0
(-1375 5525);
DISPLAY 0.489362 (-1375 5525);
PAINT SKYBLUE (-1375 5525);
FORCEPROP 0 LAST $SEC 1
J 0
(-1375 5550);
DISPLAY 0.680851 (-1375 5550);
PAINT MONO (-1375 5550);
DISPLAY INVISIBLE (-1375 5550);
FORCEPROP 0 LAST CDS_SEC 1
J 0
(-1375 5550);
DISPLAY 0.680851 (-1375 5550);
DISPLAY INVISIBLE (-1375 5550);
FORCEPROP 1 LASTPIN (-1600 5525) $PN 1
J 0
(-1588 5537);
DISPLAY 0.489362 (-1588 5537);
PAINT MONO (-1588 5537);
FORCEPROP 1 LASTPIN (-1400 5525) $PN 2
J 0
(-1438 5537);
DISPLAY 0.489362 (-1438 5537);
PAINT MONO (-1438 5537);
FORCEPROP 1 LAST VALUE 33
J 2
(-1625 5525);
DISPLAY 0.489362 (-1625 5525);
PAINT SKYBLUE (-1625 5525);
FORCEPROP 1 LAST PACK_TYPE 0402LF
J 2
(-1325 5450);
DISPLAY 0.489362 (-1325 5450);
PAINT SKYBLUE (-1325 5450);
DISPLAY INVISIBLE (-1325 5450);
FORCEPROP 1 LAST TOLERANCE 5%
J 0
(-1625 5500);
DISPLAY 0.489362 (-1625 5500);
PAINT SKYBLUE (-1625 5500);
DISPLAY INVISIBLE (-1625 5500);
FORCEPROP 1 LAST MATERIAL CHIP
J 2
(-1325 5500);
DISPLAY 0.489362 (-1325 5500);
PAINT SKYBLUE (-1325 5500);
DISPLAY INVISIBLE (-1325 5500);
FORCEPROP 1 LAST WATTAGE 1/16W
J 2
(-1575 5450);
DISPLAY 0.489362 (-1575 5450);
PAINT SKYBLUE (-1575 5450);
DISPLAY INVISIBLE (-1575 5450);
FORCEPROP 2 LAST BOM_COST MEM
J 2
(-1475 5675);
DISPLAY 0.744681 (-1475 5675);
PAINT WHITE (-1475 5675);
DISPLAY INVISIBLE (-1475 5675);
FORCEPROP 2 LAST CDS_LIB pure_quanta
J 0
(-1500 5525);
DISPLAY INVISIBLE (-1500 5525);
FORCEPROP 1 LAST PATH I27
J 0
(-1550 5675);
DISPLAY 0.978723 (-1550 5675);
PAINT WHITE (-1550 5675);
DISPLAY INVISIBLE (-1550 5675);
FORCEPROP 1 LAST PART_NUMBER CS03302JB10
J 2
(-1400 5575);
DISPLAY 0.489362 (-1400 5575);
PAINT SKYBLUE (-1400 5575);
DISPLAY INVISIBLE (-1400 5575);
FORCEADD OFFPAGE..2
(-775 5525);
FORCEPROP 2 LAST $XR0 150 
J 0
(-586 5525);
DISPLAY 0.638298 (-586 5525);
PAINT MONO (-586 5525);
FORCEPROP 2 LAST CDS_LIB standard
J 0
(-775 5525);
DISPLAY INVISIBLE (-775 5525);
FORCEPROP 1 LAST OFFPAGE TRUE
J 0
(-450 5400);
DISPLAY 0.872340 (-450 5400);
PAINT GREEN (-450 5400);
DISPLAY INVISIBLE (-450 5400);
FORCEPROP 1 LAST COMMENT_BODY TRUE
J 0
(-820 5430);
DISPLAY 0.872340 (-820 5430);
PAINT GREEN (-820 5430);
DISPLAY INVISIBLE (-820 5430);
FORCEPROP 2 LAST PATH I28
J 0
(-575 5575);
DISPLAY 0.680851 (-575 5575);
DISPLAY INVISIBLE (-575 5575);
FORCEADD Q_RES..2
(-925 5775);
FORCEPROP 1 LAST LOCATION R1338
J 0
(-880 5900);
DISPLAY 0.489362 (-880 5900);
PAINT SKYBLUE (-880 5900);
FORCEPROP 0 LAST $SEC 1
J 0
(-875 5950);
DISPLAY 0.680851 (-875 5950);
PAINT MONO (-875 5950);
DISPLAY INVISIBLE (-875 5950);
FORCEPROP 0 LAST CDS_SEC 1
J 0
(-875 5950);
DISPLAY 0.680851 (-875 5950);
DISPLAY INVISIBLE (-875 5950);
FORCEPROP 1 LASTPIN (-925 5875) $PN 1
J 0
(-920 5837);
DISPLAY 0.489362 (-920 5837);
PAINT MONO (-920 5837);
FORCEPROP 1 LASTPIN (-925 5675) $PN 2
J 0
(-920 5685);
DISPLAY 0.489362 (-920 5685);
PAINT MONO (-920 5685);
FORCEPROP 1 LAST PACK_TYPE 0402LF
J 0
(-885 5600);
DISPLAY 0.489362 (-885 5600);
PAINT SKYBLUE (-885 5600);
FORCEPROP 1 LAST VALUE 4.7K
J 0
(-880 5850);
DISPLAY 0.489362 (-880 5850);
PAINT SKYBLUE (-880 5850);
FORCEPROP 1 LAST TOLERANCE 5%
J 0
(-880 5800);
DISPLAY 0.489362 (-880 5800);
PAINT SKYBLUE (-880 5800);
FORCEPROP 1 LAST WATTAGE 1/16W
J 0
(-885 5750);
DISPLAY 0.489362 (-885 5750);
PAINT SKYBLUE (-885 5750);
FORCEPROP 1 LAST MATERIAL CHIP
J 0
(-885 5700);
DISPLAY 0.489362 (-885 5700);
PAINT SKYBLUE (-885 5700);
FORCEPROP 2 LAST CDS_LIB pure_quanta
J 0
(-925 5775);
DISPLAY INVISIBLE (-925 5775);
FORCEPROP 2 LAST BOM_COST OCP3.0 
J 0
(-875 5950);
DISPLAY 0.680851 (-875 5950);
DISPLAY INVISIBLE (-875 5950);
FORCEPROP 1 LAST PATH I29
J 0
(-875 5950);
DISPLAY 0.978723 (-875 5950);
PAINT WHITE (-875 5950);
DISPLAY INVISIBLE (-875 5950);
FORCEPROP 1 LAST PART_NUMBER CS24702JB10
J 0
(-885 5650);
DISPLAY 0.489362 (-885 5650);
PAINT SKYBLUE (-885 5650);
DISPLAY INVISIBLE (-885 5650);
FORCEADD UNIVERSAL_POWER..1
(-925 6050);
FORCEPROP 3 LASTPIN (-925 6000) SIG_NAME P3V3_AUX\g
J 0
(-915 6010);
DISPLAY 0.659574 (-915 6010);
PAINT MONO (-915 6010);
DISPLAY INVISIBLE (-915 6010);
FORCEPROP 1 LAST HDL_POWER P3V3_AUX
J 1
(-925 6100);
DISPLAY 0.489362 (-925 6100);
PAINT GREEN (-925 6100);
FORCEPROP 2 LAST BOM_COST OCP3.0 
J 0
(-925 6150);
DISPLAY 0.680851 (-925 6150);
DISPLAY INVISIBLE (-925 6150);
FORCEPROP 2 LAST CDS_LIB pure_quanta_power
J 0
(-925 6050);
DISPLAY INVISIBLE (-925 6050);
FORCEPROP 1 LAST PATH I30
J 0
(-875 6075);
DISPLAY 0.872340 (-875 6075);
PAINT AQUA (-875 6075);
DISPLAY INVISIBLE (-875 6075);
FORCEADD Q_RES..2
(-8050 1125);
FORCEPROP 1 LAST LOCATION R6143
J 0
(-8005 1250);
DISPLAY 0.978723 (-8005 1250);
FORCEPROP 0 LAST $SEC 1
J 0
(-8000 1300);
DISPLAY 0.680851 (-8000 1300);
PAINT MONO (-8000 1300);
DISPLAY INVISIBLE (-8000 1300);
FORCEPROP 0 LAST CDS_SEC 1
J 0
(-8000 1300);
DISPLAY 0.680851 (-8000 1300);
DISPLAY INVISIBLE (-8000 1300);
FORCEPROP 1 LASTPIN (-8050 1225) $PN 1
J 0
(-8045 1187);
DISPLAY 0.787234 (-8045 1187);
PAINT MONO (-8045 1187);
FORCEPROP 1 LASTPIN (-8050 1025) $PN 2
J 0
(-8045 1035);
DISPLAY 0.787234 (-8045 1035);
PAINT MONO (-8045 1035);
FORCEPROP 1 LAST WATTAGE 1/16W
J 0
(-8010 1100);
DISPLAY 0.978723 (-8010 1100);
FORCEPROP 1 LAST TOLERANCE 1%
J 0
(-8005 1150);
DISPLAY 0.978723 (-8005 1150);
FORCEPROP 1 LAST MATERIAL CHIP
J 0
(-8010 1050);
DISPLAY 0.978723 (-8010 1050);
FORCEPROP 1 LAST VALUE 1K
J 0
(-8005 1200);
DISPLAY 0.978723 (-8005 1200);
FORCEPROP 1 LAST PACK_TYPE 0402LF
J 0
(-8000 1000);
DISPLAY 0.978723 (-8000 1000);
FORCEPROP 2 LAST CDS_LIB pure_quanta
J 0
(-8050 1125);
DISPLAY INVISIBLE (-8050 1125);
FORCEPROP 1 LAST PATH I36
J 0
(-8000 1300);
DISPLAY 0.978723 (-8000 1300);
PAINT WHITE (-8000 1300);
DISPLAY INVISIBLE (-8000 1300);
FORCEPROP 1 LAST PART_NUMBER CS21002FB06
J 0
(-8010 1000);
DISPLAY 0.978723 (-8010 1000);
DISPLAY INVISIBLE (-8010 1000);
FORCEADD Q_RES..2
(-8050 2075);
FORCEPROP 1 LAST LOCATION R6138
J 0
(-8005 2200);
DISPLAY 0.978723 (-8005 2200);
FORCEPROP 0 LAST $SEC 1
J 0
(-8000 2250);
DISPLAY 0.680851 (-8000 2250);
PAINT MONO (-8000 2250);
DISPLAY INVISIBLE (-8000 2250);
FORCEPROP 0 LAST CDS_SEC 1
J 0
(-8000 2250);
DISPLAY 0.680851 (-8000 2250);
DISPLAY INVISIBLE (-8000 2250);
FORCEPROP 1 LASTPIN (-8050 2175) $PN 1
J 0
(-8045 2137);
DISPLAY 0.787234 (-8045 2137);
PAINT MONO (-8045 2137);
FORCEPROP 1 LASTPIN (-8050 1975) $PN 2
J 0
(-8045 1985);
DISPLAY 0.787234 (-8045 1985);
PAINT MONO (-8045 1985);
FORCEPROP 1 LAST TOLERANCE 1%
J 0
(-8005 2100);
DISPLAY 0.978723 (-8005 2100);
FORCEPROP 1 LAST VALUE 1K
J 0
(-8005 2150);
DISPLAY 0.978723 (-8005 2150);
FORCEPROP 1 LAST MATERIAL EMPTY
J 0
(-8010 2000);
DISPLAY 0.978723 (-8010 2000);
FORCEPROP 1 LAST WATTAGE 1/16W
J 0
(-8010 2050);
DISPLAY 0.978723 (-8010 2050);
FORCEPROP 1 LAST PACK_TYPE 0402LF
J 0
(-8000 1950);
DISPLAY 0.978723 (-8000 1950);
FORCEPROP 2 LAST CDS_LIB pure_quanta
J 0
(-8050 2075);
DISPLAY INVISIBLE (-8050 2075);
FORCEPROP 1 LAST PATH I39
J 0
(-8000 2250);
DISPLAY 0.978723 (-8000 2250);
PAINT WHITE (-8000 2250);
DISPLAY INVISIBLE (-8000 2250);
FORCEPROP 1 LAST PART_NUMBER CS21002FB06
J 0
(-8010 1950);
DISPLAY 0.978723 (-8010 1950);
DISPLAY INVISIBLE (-8010 1950);
FORCEADD UNIVERSAL_POWER..1
(-8700 2600);
FORCEPROP 3 LASTPIN (-8700 2550) SIG_NAME P3V3_AUX\g
J 0
(-8690 2560);
DISPLAY 0.659574 (-8690 2560);
PAINT MONO (-8690 2560);
DISPLAY INVISIBLE (-8690 2560);
FORCEPROP 1 LAST HDL_POWER P3V3_AUX
J 1
(-8700 2650);
DISPLAY 0.489362 (-8700 2650);
PAINT GREEN (-8700 2650);
FORCEPROP 2 LAST CDS_LIB pure_quanta_power
J 0
(-8700 2600);
DISPLAY INVISIBLE (-8700 2600);
FORCEPROP 1 LAST PATH I40
J 0
(-8650 2625);
DISPLAY 0.872340 (-8650 2625);
PAINT AQUA (-8650 2625);
DISPLAY INVISIBLE (-8650 2625);
FORCEADD Q_RES..2
(-8050 3400);
FORCEPROP 1 LAST LOCATION R6127
J 0
(-8005 3525);
DISPLAY 0.978723 (-8005 3525);
FORCEPROP 0 LAST $SEC 1
J 0
(-8000 3575);
DISPLAY 0.680851 (-8000 3575);
PAINT MONO (-8000 3575);
DISPLAY INVISIBLE (-8000 3575);
FORCEPROP 0 LAST CDS_SEC 1
J 0
(-8000 3575);
DISPLAY 0.680851 (-8000 3575);
DISPLAY INVISIBLE (-8000 3575);
FORCEPROP 1 LASTPIN (-8050 3500) $PN 1
J 0
(-8045 3462);
DISPLAY 0.787234 (-8045 3462);
PAINT MONO (-8045 3462);
FORCEPROP 1 LASTPIN (-8050 3300) $PN 2
J 0
(-8045 3310);
DISPLAY 0.787234 (-8045 3310);
PAINT MONO (-8045 3310);
FORCEPROP 1 LAST VALUE 1K
J 0
(-8005 3475);
DISPLAY 0.978723 (-8005 3475);
FORCEPROP 1 LAST TOLERANCE 1%
J 0
(-8005 3425);
DISPLAY 0.978723 (-8005 3425);
FORCEPROP 1 LAST MATERIAL CHIP
J 0
(-8010 3325);
DISPLAY 0.978723 (-8010 3325);
FORCEPROP 1 LAST PACK_TYPE 0402LF
J 0
(-8000 3275);
DISPLAY 0.978723 (-8000 3275);
FORCEPROP 1 LAST WATTAGE 1/16W
J 0
(-8010 3375);
DISPLAY 0.978723 (-8010 3375);
FORCEPROP 2 LAST CDS_LIB pure_quanta
J 0
(-8050 3400);
DISPLAY INVISIBLE (-8050 3400);
FORCEPROP 1 LAST PATH I46
J 0
(-8000 3575);
DISPLAY 0.978723 (-8000 3575);
PAINT WHITE (-8000 3575);
DISPLAY INVISIBLE (-8000 3575);
FORCEPROP 1 LAST PART_NUMBER CS21002FB06
J 0
(-8010 3275);
DISPLAY 0.978723 (-8010 3275);
DISPLAY INVISIBLE (-8010 3275);
FORCEADD UNIVERSAL_POWER..1
(-8700 4875);
FORCEPROP 3 LASTPIN (-8700 4825) SIG_NAME PVDD18_S5_P0\g
J 0
(-8690 4835);
DISPLAY 0.659574 (-8690 4835);
PAINT MONO (-8690 4835);
DISPLAY INVISIBLE (-8690 4835);
FORCEPROP 1 LAST HDL_POWER PVDD18_S5_P0
J 1
(-8700 4925);
DISPLAY 0.489362 (-8700 4925);
PAINT GREEN (-8700 4925);
FORCEPROP 2 LAST CDS_LIB pure_quanta_power
J 0
(-8700 4875);
DISPLAY INVISIBLE (-8700 4875);
FORCEPROP 1 LAST PATH I48
J 0
(-8650 4900);
DISPLAY 0.872340 (-8650 4900);
PAINT AQUA (-8650 4900);
DISPLAY INVISIBLE (-8650 4900);
FORCEADD Q_RES..2
(-8050 4350);
FORCEPROP 1 LAST LOCATION R6122
J 0
(-8005 4475);
DISPLAY 0.978723 (-8005 4475);
FORCEPROP 0 LAST $SEC 1
J 0
(-8000 4525);
DISPLAY 0.680851 (-8000 4525);
PAINT MONO (-8000 4525);
DISPLAY INVISIBLE (-8000 4525);
FORCEPROP 0 LAST CDS_SEC 1
J 0
(-8000 4525);
DISPLAY 0.680851 (-8000 4525);
DISPLAY INVISIBLE (-8000 4525);
FORCEPROP 1 LASTPIN (-8050 4450) $PN 1
J 0
(-8045 4412);
DISPLAY 0.787234 (-8045 4412);
PAINT MONO (-8045 4412);
FORCEPROP 1 LASTPIN (-8050 4250) $PN 2
J 0
(-8045 4260);
DISPLAY 0.787234 (-8045 4260);
PAINT MONO (-8045 4260);
FORCEPROP 1 LAST MATERIAL EMPTY
J 0
(-8010 4275);
DISPLAY 0.978723 (-8010 4275);
FORCEPROP 1 LAST PACK_TYPE 0402LF
J 0
(-8000 4225);
DISPLAY 0.978723 (-8000 4225);
FORCEPROP 1 LAST WATTAGE 1/16W
J 0
(-8010 4325);
DISPLAY 0.978723 (-8010 4325);
FORCEPROP 1 LAST TOLERANCE 1%
J 0
(-8005 4375);
DISPLAY 0.978723 (-8005 4375);
FORCEPROP 1 LAST VALUE 1K
J 0
(-8005 4425);
DISPLAY 0.978723 (-8005 4425);
FORCEPROP 2 LAST CDS_LIB pure_quanta
J 0
(-8050 4350);
DISPLAY INVISIBLE (-8050 4350);
FORCEPROP 1 LAST PATH I50
J 0
(-8000 4525);
DISPLAY 0.978723 (-8000 4525);
PAINT WHITE (-8000 4525);
DISPLAY INVISIBLE (-8000 4525);
FORCEPROP 1 LAST PART_NUMBER CS21002FB06
J 0
(-8010 4225);
DISPLAY 0.978723 (-8010 4225);
DISPLAY INVISIBLE (-8010 4225);
FORCEADD Q_RES..2
(-7700 1125);
FORCEPROP 1 LAST LOCATION R6144
J 0
(-7655 1250);
DISPLAY 0.978723 (-7655 1250);
FORCEPROP 0 LAST $SEC 1
J 0
(-7650 1300);
DISPLAY 0.680851 (-7650 1300);
PAINT MONO (-7650 1300);
DISPLAY INVISIBLE (-7650 1300);
FORCEPROP 0 LAST CDS_SEC 1
J 0
(-7650 1300);
DISPLAY 0.680851 (-7650 1300);
DISPLAY INVISIBLE (-7650 1300);
FORCEPROP 1 LASTPIN (-7700 1225) $PN 1
J 0
(-7695 1187);
DISPLAY 0.787234 (-7695 1187);
PAINT MONO (-7695 1187);
FORCEPROP 1 LASTPIN (-7700 1025) $PN 2
J 0
(-7695 1035);
DISPLAY 0.787234 (-7695 1035);
PAINT MONO (-7695 1035);
FORCEPROP 1 LAST MATERIAL CHIP
J 0
(-7660 1050);
DISPLAY 0.978723 (-7660 1050);
FORCEPROP 1 LAST WATTAGE 1/16W
J 0
(-7660 1100);
DISPLAY 0.978723 (-7660 1100);
FORCEPROP 1 LAST TOLERANCE 1%
J 0
(-7655 1150);
DISPLAY 0.978723 (-7655 1150);
FORCEPROP 1 LAST VALUE 1K
J 0
(-7655 1200);
DISPLAY 0.978723 (-7655 1200);
FORCEPROP 1 LAST PACK_TYPE 0402LF
J 0
(-7650 1000);
DISPLAY 0.978723 (-7650 1000);
FORCEPROP 2 LAST CDS_LIB pure_quanta
J 0
(-7700 1125);
DISPLAY INVISIBLE (-7700 1125);
FORCEPROP 1 LAST PATH I52
J 0
(-7650 1300);
DISPLAY 0.978723 (-7650 1300);
PAINT WHITE (-7650 1300);
DISPLAY INVISIBLE (-7650 1300);
FORCEPROP 1 LAST PART_NUMBER CS21002FB06
J 0
(-7660 1000);
DISPLAY 0.978723 (-7660 1000);
DISPLAY INVISIBLE (-7660 1000);
FORCEADD Q_RES..2
(-7350 1125);
FORCEPROP 1 LAST LOCATION R6145
J 0
(-7305 1250);
DISPLAY 0.978723 (-7305 1250);
FORCEPROP 0 LAST $SEC 1
J 0
(-7300 1300);
DISPLAY 0.680851 (-7300 1300);
PAINT MONO (-7300 1300);
DISPLAY INVISIBLE (-7300 1300);
FORCEPROP 0 LAST CDS_SEC 1
J 0
(-7300 1300);
DISPLAY 0.680851 (-7300 1300);
DISPLAY INVISIBLE (-7300 1300);
FORCEPROP 1 LASTPIN (-7350 1225) $PN 1
J 0
(-7345 1187);
DISPLAY 0.787234 (-7345 1187);
PAINT MONO (-7345 1187);
FORCEPROP 1 LASTPIN (-7350 1025) $PN 2
J 0
(-7345 1035);
DISPLAY 0.787234 (-7345 1035);
PAINT MONO (-7345 1035);
FORCEPROP 1 LAST TOLERANCE 1%
J 0
(-7305 1150);
DISPLAY 0.978723 (-7305 1150);
FORCEPROP 1 LAST WATTAGE 1/16W
J 0
(-7310 1100);
DISPLAY 0.978723 (-7310 1100);
FORCEPROP 1 LAST MATERIAL CHIP
J 0
(-7310 1050);
DISPLAY 0.978723 (-7310 1050);
FORCEPROP 1 LAST VALUE 1K
J 0
(-7305 1200);
DISPLAY 0.978723 (-7305 1200);
FORCEPROP 1 LAST PACK_TYPE 0402LF
J 0
(-7310 950);
DISPLAY 0.978723 (-7310 950);
FORCEPROP 2 LAST CDS_LIB pure_quanta
J 0
(-7350 1125);
DISPLAY INVISIBLE (-7350 1125);
FORCEPROP 1 LAST PATH I54
J 0
(-7300 1300);
DISPLAY 0.978723 (-7300 1300);
PAINT WHITE (-7300 1300);
DISPLAY INVISIBLE (-7300 1300);
FORCEPROP 1 LAST PART_NUMBER CS21002FB06
J 0
(-7310 1000);
DISPLAY 0.978723 (-7310 1000);
DISPLAY INVISIBLE (-7310 1000);
FORCEADD Q_RES..2
(-7700 2075);
FORCEPROP 1 LAST LOCATION R6139
J 0
(-7655 2200);
DISPLAY 0.978723 (-7655 2200);
FORCEPROP 0 LAST $SEC 1
J 0
(-7650 2250);
DISPLAY 0.680851 (-7650 2250);
PAINT MONO (-7650 2250);
DISPLAY INVISIBLE (-7650 2250);
FORCEPROP 0 LAST CDS_SEC 1
J 0
(-7650 2250);
DISPLAY 0.680851 (-7650 2250);
DISPLAY INVISIBLE (-7650 2250);
FORCEPROP 1 LASTPIN (-7700 2175) $PN 1
J 0
(-7695 2137);
DISPLAY 0.787234 (-7695 2137);
PAINT MONO (-7695 2137);
FORCEPROP 1 LASTPIN (-7700 1975) $PN 2
J 0
(-7695 1985);
DISPLAY 0.787234 (-7695 1985);
PAINT MONO (-7695 1985);
FORCEPROP 1 LAST PACK_TYPE 0402LF
J 0
(-7650 1950);
DISPLAY 0.978723 (-7650 1950);
FORCEPROP 1 LAST TOLERANCE 1%
J 0
(-7655 2100);
DISPLAY 0.978723 (-7655 2100);
FORCEPROP 1 LAST VALUE 1K
J 0
(-7655 2150);
DISPLAY 0.978723 (-7655 2150);
FORCEPROP 1 LAST WATTAGE 1/16W
J 0
(-7660 2050);
DISPLAY 0.978723 (-7660 2050);
FORCEPROP 1 LAST MATERIAL EMPTY
J 0
(-7660 2000);
DISPLAY 0.978723 (-7660 2000);
FORCEPROP 2 LAST CDS_LIB pure_quanta
J 0
(-7700 2075);
DISPLAY INVISIBLE (-7700 2075);
FORCEPROP 1 LAST PATH I55
J 0
(-7650 2250);
DISPLAY 0.978723 (-7650 2250);
PAINT WHITE (-7650 2250);
DISPLAY INVISIBLE (-7650 2250);
FORCEPROP 1 LAST PART_NUMBER CS21002FB06
J 0
(-7660 1950);
DISPLAY 0.978723 (-7660 1950);
DISPLAY INVISIBLE (-7660 1950);
FORCEADD Q_RES..2
(-7350 2075);
FORCEPROP 1 LAST LOCATION R6140
J 0
(-7305 2200);
DISPLAY 0.978723 (-7305 2200);
FORCEPROP 0 LAST $SEC 1
J 0
(-7300 2250);
DISPLAY 0.680851 (-7300 2250);
PAINT MONO (-7300 2250);
DISPLAY INVISIBLE (-7300 2250);
FORCEPROP 0 LAST CDS_SEC 1
J 0
(-7300 2250);
DISPLAY 0.680851 (-7300 2250);
DISPLAY INVISIBLE (-7300 2250);
FORCEPROP 1 LASTPIN (-7350 2175) $PN 1
J 0
(-7345 2137);
DISPLAY 0.787234 (-7345 2137);
PAINT MONO (-7345 2137);
FORCEPROP 1 LASTPIN (-7350 1975) $PN 2
J 0
(-7345 1985);
DISPLAY 0.787234 (-7345 1985);
PAINT MONO (-7345 1985);
FORCEPROP 1 LAST MATERIAL EMPTY
J 0
(-7310 2000);
DISPLAY 0.978723 (-7310 2000);
FORCEPROP 1 LAST PACK_TYPE 0402LF
J 0
(-7310 1900);
DISPLAY 0.978723 (-7310 1900);
FORCEPROP 1 LAST VALUE 1K
J 0
(-7305 2150);
DISPLAY 0.978723 (-7305 2150);
FORCEPROP 1 LAST TOLERANCE 1%
J 0
(-7305 2100);
DISPLAY 0.978723 (-7305 2100);
FORCEPROP 1 LAST WATTAGE 1/16W
J 0
(-7310 2050);
DISPLAY 0.978723 (-7310 2050);
FORCEPROP 2 LAST CDS_LIB pure_quanta
J 0
(-7350 2075);
DISPLAY INVISIBLE (-7350 2075);
FORCEPROP 1 LAST PATH I56
J 0
(-7300 2250);
DISPLAY 0.978723 (-7300 2250);
PAINT WHITE (-7300 2250);
DISPLAY INVISIBLE (-7300 2250);
FORCEPROP 1 LAST PART_NUMBER CS21002FB06
J 0
(-7310 1950);
DISPLAY 0.978723 (-7310 1950);
DISPLAY INVISIBLE (-7310 1950);
FORCEADD OFFPAGE..2
(-5975 1400);
FORCEPROP 2 LAST $XR0 80 
J 0
(-5786 1400);
DISPLAY 0.638298 (-5786 1400);
PAINT MONO (-5786 1400);
FORCEPROP 2 LAST CDS_LIB standard
J 0
(-5975 1400);
DISPLAY INVISIBLE (-5975 1400);
FORCEPROP 1 LAST OFFPAGE TRUE
J 0
(-5650 1275);
DISPLAY 0.872340 (-5650 1275);
PAINT GREEN (-5650 1275);
DISPLAY INVISIBLE (-5650 1275);
FORCEPROP 1 LAST COMMENT_BODY TRUE
J 0
(-6020 1305);
DISPLAY 0.872340 (-6020 1305);
PAINT GREEN (-6020 1305);
DISPLAY INVISIBLE (-6020 1305);
FORCEPROP 2 LAST PATH I57
J 0
(-5775 1450);
DISPLAY 0.680851 (-5775 1450);
DISPLAY INVISIBLE (-5775 1450);
FORCEADD OFFPAGE..2
(-5975 1500);
FORCEPROP 2 LAST $XR0 80 
J 0
(-5786 1500);
DISPLAY 0.638298 (-5786 1500);
PAINT MONO (-5786 1500);
FORCEPROP 2 LAST CDS_LIB standard
J 0
(-5975 1500);
DISPLAY INVISIBLE (-5975 1500);
FORCEPROP 1 LAST OFFPAGE TRUE
J 0
(-5650 1375);
DISPLAY 0.872340 (-5650 1375);
PAINT GREEN (-5650 1375);
DISPLAY INVISIBLE (-5650 1375);
FORCEPROP 1 LAST COMMENT_BODY TRUE
J 0
(-6020 1405);
DISPLAY 0.872340 (-6020 1405);
PAINT GREEN (-6020 1405);
DISPLAY INVISIBLE (-6020 1405);
FORCEPROP 2 LAST PATH I58
J 0
(-5775 1550);
DISPLAY 0.680851 (-5775 1550);
DISPLAY INVISIBLE (-5775 1550);
FORCEADD OFFPAGE..2
(-5975 1600);
FORCEPROP 2 LAST $XR0 80 
J 0
(-5786 1600);
DISPLAY 0.638298 (-5786 1600);
PAINT MONO (-5786 1600);
FORCEPROP 2 LAST CDS_LIB standard
J 0
(-5975 1600);
DISPLAY INVISIBLE (-5975 1600);
FORCEPROP 1 LAST OFFPAGE TRUE
J 0
(-5650 1475);
DISPLAY 0.872340 (-5650 1475);
PAINT GREEN (-5650 1475);
DISPLAY INVISIBLE (-5650 1475);
FORCEPROP 1 LAST COMMENT_BODY TRUE
J 0
(-6020 1505);
DISPLAY 0.872340 (-6020 1505);
PAINT GREEN (-6020 1505);
DISPLAY INVISIBLE (-6020 1505);
FORCEPROP 2 LAST PATH I59
J 0
(-5775 1650);
DISPLAY 0.680851 (-5775 1650);
DISPLAY INVISIBLE (-5775 1650);
FORCEADD OFFPAGE..2
(-5975 1700);
FORCEPROP 2 LAST $XR0 80 
J 0
(-5786 1700);
DISPLAY 0.638298 (-5786 1700);
PAINT MONO (-5786 1700);
FORCEPROP 2 LAST CDS_LIB standard
J 0
(-5975 1700);
DISPLAY INVISIBLE (-5975 1700);
FORCEPROP 1 LAST OFFPAGE TRUE
J 0
(-5650 1575);
DISPLAY 0.872340 (-5650 1575);
PAINT GREEN (-5650 1575);
DISPLAY INVISIBLE (-5650 1575);
FORCEPROP 1 LAST COMMENT_BODY TRUE
J 0
(-6020 1605);
DISPLAY 0.872340 (-6020 1605);
PAINT GREEN (-6020 1605);
DISPLAY INVISIBLE (-6020 1605);
FORCEPROP 2 LAST PATH I60
J 0
(-5775 1750);
DISPLAY 0.680851 (-5775 1750);
DISPLAY INVISIBLE (-5775 1750);
FORCEADD OFFPAGE..2
(-5975 1800);
FORCEPROP 2 LAST $XR0 80 
J 0
(-5786 1800);
DISPLAY 0.638298 (-5786 1800);
PAINT MONO (-5786 1800);
FORCEPROP 2 LAST CDS_LIB standard
J 0
(-5975 1800);
DISPLAY INVISIBLE (-5975 1800);
FORCEPROP 1 LAST OFFPAGE TRUE
J 0
(-5650 1675);
DISPLAY 0.872340 (-5650 1675);
PAINT GREEN (-5650 1675);
DISPLAY INVISIBLE (-5650 1675);
FORCEPROP 1 LAST COMMENT_BODY TRUE
J 0
(-6020 1705);
DISPLAY 0.872340 (-6020 1705);
PAINT GREEN (-6020 1705);
DISPLAY INVISIBLE (-6020 1705);
FORCEPROP 2 LAST PATH I61
J 0
(-5775 1850);
DISPLAY 0.680851 (-5775 1850);
DISPLAY INVISIBLE (-5775 1850);
FORCEADD Q_RES..2
(-7700 3400);
FORCEPROP 1 LAST LOCATION R6128
J 0
(-7655 3525);
DISPLAY 0.978723 (-7655 3525);
FORCEPROP 0 LAST $SEC 1
J 0
(-7650 3575);
DISPLAY 0.680851 (-7650 3575);
PAINT MONO (-7650 3575);
DISPLAY INVISIBLE (-7650 3575);
FORCEPROP 0 LAST CDS_SEC 1
J 0
(-7650 3575);
DISPLAY 0.680851 (-7650 3575);
DISPLAY INVISIBLE (-7650 3575);
FORCEPROP 1 LASTPIN (-7700 3500) $PN 1
J 0
(-7695 3462);
DISPLAY 0.787234 (-7695 3462);
PAINT MONO (-7695 3462);
FORCEPROP 1 LASTPIN (-7700 3300) $PN 2
J 0
(-7695 3310);
DISPLAY 0.787234 (-7695 3310);
PAINT MONO (-7695 3310);
FORCEPROP 1 LAST TOLERANCE 1%
J 0
(-7655 3425);
DISPLAY 0.978723 (-7655 3425);
FORCEPROP 1 LAST WATTAGE 1/16W
J 0
(-7660 3375);
DISPLAY 0.978723 (-7660 3375);
FORCEPROP 1 LAST VALUE 1K
J 0
(-7655 3475);
DISPLAY 0.978723 (-7655 3475);
FORCEPROP 1 LAST MATERIAL CHIP
J 0
(-7660 3325);
DISPLAY 0.978723 (-7660 3325);
FORCEPROP 1 LAST PACK_TYPE 0402LF
J 0
(-7650 3275);
DISPLAY 0.978723 (-7650 3275);
FORCEPROP 2 LAST CDS_LIB pure_quanta
J 0
(-7700 3400);
DISPLAY INVISIBLE (-7700 3400);
FORCEPROP 1 LAST PATH I64
J 0
(-7650 3575);
DISPLAY 0.978723 (-7650 3575);
PAINT WHITE (-7650 3575);
DISPLAY INVISIBLE (-7650 3575);
FORCEPROP 1 LAST PART_NUMBER CS21002FB06
J 0
(-7660 3275);
DISPLAY 0.978723 (-7660 3275);
DISPLAY INVISIBLE (-7660 3275);
FORCEADD Q_RES..2
(-7350 3400);
FORCEPROP 1 LAST LOCATION R6129
J 0
(-7305 3525);
DISPLAY 0.978723 (-7305 3525);
FORCEPROP 0 LAST $SEC 1
J 0
(-7300 3575);
DISPLAY 0.680851 (-7300 3575);
PAINT MONO (-7300 3575);
DISPLAY INVISIBLE (-7300 3575);
FORCEPROP 0 LAST CDS_SEC 1
J 0
(-7300 3575);
DISPLAY 0.680851 (-7300 3575);
DISPLAY INVISIBLE (-7300 3575);
FORCEPROP 1 LASTPIN (-7350 3500) $PN 1
J 0
(-7345 3462);
DISPLAY 0.787234 (-7345 3462);
PAINT MONO (-7345 3462);
FORCEPROP 1 LASTPIN (-7350 3300) $PN 2
J 0
(-7345 3310);
DISPLAY 0.787234 (-7345 3310);
PAINT MONO (-7345 3310);
FORCEPROP 1 LAST PACK_TYPE 0402LF
J 0
(-7310 3225);
DISPLAY 0.978723 (-7310 3225);
FORCEPROP 1 LAST WATTAGE 1/16W
J 0
(-7310 3375);
DISPLAY 0.978723 (-7310 3375);
FORCEPROP 1 LAST VALUE 1K
J 0
(-7305 3475);
DISPLAY 0.978723 (-7305 3475);
FORCEPROP 1 LAST TOLERANCE 1%
J 0
(-7305 3425);
DISPLAY 0.978723 (-7305 3425);
FORCEPROP 1 LAST MATERIAL CHIP
J 0
(-7310 3325);
DISPLAY 0.978723 (-7310 3325);
FORCEPROP 2 LAST CDS_LIB pure_quanta
J 0
(-7350 3400);
DISPLAY INVISIBLE (-7350 3400);
FORCEPROP 1 LAST PATH I65
J 0
(-7300 3575);
DISPLAY 0.978723 (-7300 3575);
PAINT WHITE (-7300 3575);
DISPLAY INVISIBLE (-7300 3575);
FORCEPROP 1 LAST PART_NUMBER CS21002FB06
J 0
(-7310 3275);
DISPLAY 0.978723 (-7310 3275);
DISPLAY INVISIBLE (-7310 3275);
FORCEADD OFFPAGE..2
(-5975 3675);
FORCEPROP 2 LAST $XR0 28 
J 0
(-5786 3675);
DISPLAY 0.638298 (-5786 3675);
PAINT MONO (-5786 3675);
FORCEPROP 2 LAST CDS_LIB standard
J 0
(-5975 3675);
DISPLAY INVISIBLE (-5975 3675);
FORCEPROP 1 LAST OFFPAGE TRUE
J 0
(-5650 3550);
DISPLAY 0.872340 (-5650 3550);
PAINT GREEN (-5650 3550);
DISPLAY INVISIBLE (-5650 3550);
FORCEPROP 1 LAST COMMENT_BODY TRUE
J 0
(-6020 3580);
DISPLAY 0.872340 (-6020 3580);
PAINT GREEN (-6020 3580);
DISPLAY INVISIBLE (-6020 3580);
FORCEPROP 2 LAST PATH I66
J 0
(-5775 3725);
DISPLAY 0.680851 (-5775 3725);
DISPLAY INVISIBLE (-5775 3725);
FORCEADD OFFPAGE..2
(-5975 3775);
FORCEPROP 2 LAST $XR0 28 
J 0
(-5786 3775);
DISPLAY 0.638298 (-5786 3775);
PAINT MONO (-5786 3775);
FORCEPROP 2 LAST CDS_LIB standard
J 0
(-5975 3775);
DISPLAY INVISIBLE (-5975 3775);
FORCEPROP 1 LAST OFFPAGE TRUE
J 0
(-5650 3650);
DISPLAY 0.872340 (-5650 3650);
PAINT GREEN (-5650 3650);
DISPLAY INVISIBLE (-5650 3650);
FORCEPROP 1 LAST COMMENT_BODY TRUE
J 0
(-6020 3680);
DISPLAY 0.872340 (-6020 3680);
PAINT GREEN (-6020 3680);
DISPLAY INVISIBLE (-6020 3680);
FORCEPROP 2 LAST PATH I67
J 0
(-5775 3825);
DISPLAY 0.680851 (-5775 3825);
DISPLAY INVISIBLE (-5775 3825);
FORCEADD OFFPAGE..2
(-5975 3875);
FORCEPROP 2 LAST $XR0 28 
J 0
(-5786 3875);
DISPLAY 0.638298 (-5786 3875);
PAINT MONO (-5786 3875);
FORCEPROP 2 LAST CDS_LIB standard
J 0
(-5975 3875);
DISPLAY INVISIBLE (-5975 3875);
FORCEPROP 1 LAST OFFPAGE TRUE
J 0
(-5650 3750);
DISPLAY 0.872340 (-5650 3750);
PAINT GREEN (-5650 3750);
DISPLAY INVISIBLE (-5650 3750);
FORCEPROP 1 LAST COMMENT_BODY TRUE
J 0
(-6020 3780);
DISPLAY 0.872340 (-6020 3780);
PAINT GREEN (-6020 3780);
DISPLAY INVISIBLE (-6020 3780);
FORCEPROP 2 LAST PATH I68
J 0
(-5775 3925);
DISPLAY 0.680851 (-5775 3925);
DISPLAY INVISIBLE (-5775 3925);
FORCEADD OFFPAGE..2
(-5975 3975);
FORCEPROP 2 LAST $XR0 28 
J 0
(-5786 3975);
DISPLAY 0.638298 (-5786 3975);
PAINT MONO (-5786 3975);
FORCEPROP 2 LAST CDS_LIB standard
J 0
(-5975 3975);
DISPLAY INVISIBLE (-5975 3975);
FORCEPROP 1 LAST OFFPAGE TRUE
J 0
(-5650 3850);
DISPLAY 0.872340 (-5650 3850);
PAINT GREEN (-5650 3850);
DISPLAY INVISIBLE (-5650 3850);
FORCEPROP 1 LAST COMMENT_BODY TRUE
J 0
(-6020 3880);
DISPLAY 0.872340 (-6020 3880);
PAINT GREEN (-6020 3880);
DISPLAY INVISIBLE (-6020 3880);
FORCEPROP 2 LAST PATH I69
J 0
(-5775 4025);
DISPLAY 0.680851 (-5775 4025);
DISPLAY INVISIBLE (-5775 4025);
FORCEADD OFFPAGE..2
(-5975 4075);
FORCEPROP 2 LAST $XR0 28 
J 0
(-5786 4075);
DISPLAY 0.638298 (-5786 4075);
PAINT MONO (-5786 4075);
FORCEPROP 2 LAST CDS_LIB standard
J 0
(-5975 4075);
DISPLAY INVISIBLE (-5975 4075);
FORCEPROP 1 LAST OFFPAGE TRUE
J 0
(-5650 3950);
DISPLAY 0.872340 (-5650 3950);
PAINT GREEN (-5650 3950);
DISPLAY INVISIBLE (-5650 3950);
FORCEPROP 1 LAST COMMENT_BODY TRUE
J 0
(-6020 3980);
DISPLAY 0.872340 (-6020 3980);
PAINT GREEN (-6020 3980);
DISPLAY INVISIBLE (-6020 3980);
FORCEPROP 2 LAST PATH I70
J 0
(-5775 4125);
DISPLAY 0.680851 (-5775 4125);
DISPLAY INVISIBLE (-5775 4125);
FORCEADD Q_RES..2
(-7700 4350);
FORCEPROP 1 LAST LOCATION R6123
J 0
(-7655 4475);
DISPLAY 0.978723 (-7655 4475);
FORCEPROP 0 LAST $SEC 1
J 0
(-7650 4525);
DISPLAY 0.680851 (-7650 4525);
PAINT MONO (-7650 4525);
DISPLAY INVISIBLE (-7650 4525);
FORCEPROP 0 LAST CDS_SEC 1
J 0
(-7650 4525);
DISPLAY 0.680851 (-7650 4525);
DISPLAY INVISIBLE (-7650 4525);
FORCEPROP 1 LASTPIN (-7700 4450) $PN 1
J 0
(-7695 4412);
DISPLAY 0.787234 (-7695 4412);
PAINT MONO (-7695 4412);
FORCEPROP 1 LASTPIN (-7700 4250) $PN 2
J 0
(-7695 4260);
DISPLAY 0.787234 (-7695 4260);
PAINT MONO (-7695 4260);
FORCEPROP 1 LAST VALUE 1K
J 0
(-7655 4425);
DISPLAY 0.978723 (-7655 4425);
FORCEPROP 1 LAST MATERIAL EMPTY
J 0
(-7660 4275);
DISPLAY 0.978723 (-7660 4275);
FORCEPROP 1 LAST WATTAGE 1/16W
J 0
(-7660 4325);
DISPLAY 0.978723 (-7660 4325);
FORCEPROP 1 LAST TOLERANCE 1%
J 0
(-7655 4375);
DISPLAY 0.978723 (-7655 4375);
FORCEPROP 1 LAST PACK_TYPE 0402LF
J 0
(-7650 4225);
DISPLAY 0.978723 (-7650 4225);
FORCEPROP 2 LAST CDS_LIB pure_quanta
J 0
(-7700 4350);
DISPLAY INVISIBLE (-7700 4350);
FORCEPROP 1 LAST PATH I71
J 0
(-7650 4525);
DISPLAY 0.978723 (-7650 4525);
PAINT WHITE (-7650 4525);
DISPLAY INVISIBLE (-7650 4525);
FORCEPROP 1 LAST PART_NUMBER CS21002FB06
J 0
(-7660 4225);
DISPLAY 0.978723 (-7660 4225);
DISPLAY INVISIBLE (-7660 4225);
FORCEADD Q_RES..2
(-7350 4350);
FORCEPROP 1 LAST LOCATION R6124
J 0
(-7305 4475);
DISPLAY 0.978723 (-7305 4475);
FORCEPROP 0 LAST $SEC 1
J 0
(-7300 4525);
DISPLAY 0.680851 (-7300 4525);
PAINT MONO (-7300 4525);
DISPLAY INVISIBLE (-7300 4525);
FORCEPROP 0 LAST CDS_SEC 1
J 0
(-7300 4525);
DISPLAY 0.680851 (-7300 4525);
DISPLAY INVISIBLE (-7300 4525);
FORCEPROP 1 LASTPIN (-7350 4450) $PN 1
J 0
(-7345 4412);
DISPLAY 0.787234 (-7345 4412);
PAINT MONO (-7345 4412);
FORCEPROP 1 LASTPIN (-7350 4250) $PN 2
J 0
(-7345 4260);
DISPLAY 0.787234 (-7345 4260);
PAINT MONO (-7345 4260);
FORCEPROP 1 LAST TOLERANCE 1%
J 0
(-7305 4375);
DISPLAY 0.978723 (-7305 4375);
FORCEPROP 1 LAST VALUE 1K
J 0
(-7305 4425);
DISPLAY 0.978723 (-7305 4425);
FORCEPROP 1 LAST MATERIAL EMPTY
J 0
(-7310 4275);
DISPLAY 0.978723 (-7310 4275);
FORCEPROP 1 LAST WATTAGE 1/16W
J 0
(-7310 4325);
DISPLAY 0.978723 (-7310 4325);
FORCEPROP 1 LAST PACK_TYPE 0402LF
J 0
(-7310 4175);
DISPLAY 0.978723 (-7310 4175);
FORCEPROP 2 LAST CDS_LIB pure_quanta
J 0
(-7350 4350);
DISPLAY INVISIBLE (-7350 4350);
FORCEPROP 1 LAST PATH I72
J 0
(-7300 4525);
DISPLAY 0.978723 (-7300 4525);
PAINT WHITE (-7300 4525);
DISPLAY INVISIBLE (-7300 4525);
FORCEPROP 1 LAST PART_NUMBER CS21002FB06
J 0
(-7310 4225);
DISPLAY 0.978723 (-7310 4225);
DISPLAY INVISIBLE (-7310 4225);
FORCEADD UNIVERSAL_POWER..1
(-3650 2525);
FORCEPROP 3 LASTPIN (-3650 2475) SIG_NAME P1V8_AUX\g
J 0
(-3640 2485);
DISPLAY 0.659574 (-3640 2485);
PAINT MONO (-3640 2485);
DISPLAY INVISIBLE (-3640 2485);
FORCEPROP 1 LAST HDL_POWER P1V8_AUX
J 1
(-3650 2575);
DISPLAY 0.489362 (-3650 2575);
PAINT GREEN (-3650 2575);
FORCEPROP 2 LAST CDS_LIB pure_quanta_power
J 0
(-3650 2525);
DISPLAY INVISIBLE (-3650 2525);
FORCEPROP 1 LAST PATH I82
J 0
(-3600 2550);
DISPLAY 0.872340 (-3600 2550);
PAINT AQUA (-3600 2550);
DISPLAY INVISIBLE (-3600 2550);
FORCEADD UNIVERSAL_GND..1
(-2500 5250);
FORCEPROP 3 LASTPIN (-2500 5300) SIG_NAME GND\g
J 0
(-2490 5310);
DISPLAY 0.659574 (-2490 5310);
PAINT MONO (-2490 5310);
DISPLAY INVISIBLE (-2490 5310);
FORCEPROP 2 LAST CDS_LIB pure_quanta_power
J 0
(-2500 5250);
DISPLAY INVISIBLE (-2500 5250);
FORCEPROP 2 LAST BOM_COST OCP3.0 
J 0
(-2700 5325);
DISPLAY 0.680851 (-2700 5325);
DISPLAY INVISIBLE (-2700 5325);
FORCEPROP 1 LAST HDL_POWER GND
J 1
(-2475 5175);
DISPLAY 0.872340 (-2475 5175);
PAINT GREEN (-2475 5175);
DISPLAY INVISIBLE (-2475 5175);
FORCEPROP 1 LAST PATH I9
J 0
(-2425 5250);
DISPLAY 0.872340 (-2425 5250);
PAINT AQUA (-2425 5250);
DISPLAY INVISIBLE (-2425 5250);
FORCEADD OFFPAGE..2
(-1575 1425);
FORCEPROP 2 LAST $XR0 82 
J 0
(-1386 1425);
DISPLAY 0.638298 (-1386 1425);
PAINT MONO (-1386 1425);
FORCEPROP 2 LAST CDS_LIB standard
J 0
(-1575 1425);
DISPLAY INVISIBLE (-1575 1425);
FORCEPROP 1 LAST OFFPAGE TRUE
J 0
(-1250 1300);
DISPLAY 0.872340 (-1250 1300);
PAINT GREEN (-1250 1300);
DISPLAY INVISIBLE (-1250 1300);
FORCEPROP 1 LAST COMMENT_BODY TRUE
J 0
(-1620 1330);
DISPLAY 0.872340 (-1620 1330);
PAINT GREEN (-1620 1330);
DISPLAY INVISIBLE (-1620 1330);
FORCEPROP 2 LAST PATH I92
J 0
(-1375 1475);
DISPLAY 0.680851 (-1375 1475);
DISPLAY INVISIBLE (-1375 1475);
FORCEADD OFFPAGE..2
(-1575 1525);
FORCEPROP 2 LAST $XR0 82 
J 0
(-1386 1525);
DISPLAY 0.638298 (-1386 1525);
PAINT MONO (-1386 1525);
FORCEPROP 2 LAST CDS_LIB standard
J 0
(-1575 1525);
DISPLAY INVISIBLE (-1575 1525);
FORCEPROP 1 LAST OFFPAGE TRUE
J 0
(-1250 1400);
DISPLAY 0.872340 (-1250 1400);
PAINT GREEN (-1250 1400);
DISPLAY INVISIBLE (-1250 1400);
FORCEPROP 1 LAST COMMENT_BODY TRUE
J 0
(-1620 1430);
DISPLAY 0.872340 (-1620 1430);
PAINT GREEN (-1620 1430);
DISPLAY INVISIBLE (-1620 1430);
FORCEPROP 2 LAST PATH I93
J 0
(-1375 1575);
DISPLAY 0.680851 (-1375 1575);
DISPLAY INVISIBLE (-1375 1575);
FORCEADD OFFPAGE..2
(-1575 3975);
FORCEPROP 2 LAST $XR0 28 
J 0
(-1386 3975);
DISPLAY 0.638298 (-1386 3975);
PAINT MONO (-1386 3975);
FORCEPROP 2 LAST CDS_LIB standard
J 0
(-1575 3975);
DISPLAY INVISIBLE (-1575 3975);
FORCEPROP 1 LAST OFFPAGE TRUE
J 0
(-1250 3850);
DISPLAY 0.872340 (-1250 3850);
PAINT GREEN (-1250 3850);
DISPLAY INVISIBLE (-1250 3850);
FORCEPROP 1 LAST COMMENT_BODY TRUE
J 0
(-1620 3880);
DISPLAY 0.872340 (-1620 3880);
PAINT GREEN (-1620 3880);
DISPLAY INVISIBLE (-1620 3880);
FORCEPROP 2 LAST PATH I94
J 0
(-1375 4025);
DISPLAY 0.680851 (-1375 4025);
DISPLAY INVISIBLE (-1375 4025);
FORCEADD OFFPAGE..2
(-1575 4075);
FORCEPROP 2 LAST $XR0 28 
J 0
(-1386 4075);
DISPLAY 0.638298 (-1386 4075);
PAINT MONO (-1386 4075);
FORCEPROP 2 LAST CDS_LIB standard
J 0
(-1575 4075);
DISPLAY INVISIBLE (-1575 4075);
FORCEPROP 1 LAST OFFPAGE TRUE
J 0
(-1250 3950);
DISPLAY 0.872340 (-1250 3950);
PAINT GREEN (-1250 3950);
DISPLAY INVISIBLE (-1250 3950);
FORCEPROP 1 LAST COMMENT_BODY TRUE
J 0
(-1620 3980);
DISPLAY 0.872340 (-1620 3980);
PAINT GREEN (-1620 3980);
DISPLAY INVISIBLE (-1620 3980);
FORCEPROP 2 LAST PATH I95
J 0
(-1375 4125);
DISPLAY 0.680851 (-1375 4125);
DISPLAY INVISIBLE (-1375 4125);
FORCEADD OFFPAGE..2
(-1575 4175);
FORCEPROP 2 LAST $XR0 28 
J 0
(-1386 4175);
DISPLAY 0.638298 (-1386 4175);
PAINT MONO (-1386 4175);
FORCEPROP 2 LAST CDS_LIB standard
J 0
(-1575 4175);
DISPLAY INVISIBLE (-1575 4175);
FORCEPROP 1 LAST OFFPAGE TRUE
J 0
(-1250 4050);
DISPLAY 0.872340 (-1250 4050);
PAINT GREEN (-1250 4050);
DISPLAY INVISIBLE (-1250 4050);
FORCEPROP 1 LAST COMMENT_BODY TRUE
J 0
(-1620 4080);
DISPLAY 0.872340 (-1620 4080);
PAINT GREEN (-1620 4080);
DISPLAY INVISIBLE (-1620 4080);
FORCEPROP 2 LAST PATH I96
J 0
(-1375 4225);
DISPLAY 0.680851 (-1375 4225);
DISPLAY INVISIBLE (-1375 4225);
FORCEADD UNIVERSAL_POWER..1
(-3650 5175);
FORCEPROP 3 LASTPIN (-3650 5125) SIG_NAME PVDD18_S5_P0\g
J 0
(-3640 5135);
DISPLAY 0.659574 (-3640 5135);
PAINT MONO (-3640 5135);
DISPLAY INVISIBLE (-3640 5135);
FORCEPROP 1 LAST HDL_POWER PVDD18_S5_P0
J 1
(-3650 5225);
DISPLAY 0.489362 (-3650 5225);
PAINT GREEN (-3650 5225);
FORCEPROP 2 LAST CDS_LIB pure_quanta_power
J 0
(-3650 5175);
DISPLAY INVISIBLE (-3650 5175);
FORCEPROP 1 LAST PATH I97
J 0
(-3600 5200);
DISPLAY 0.872340 (-3600 5200);
PAINT AQUA (-3600 5200);
DISPLAY INVISIBLE (-3600 5200);
FORCEADD OFFPAGE..2
(-1575 1325);
FORCEPROP 2 LAST $XR0 82 
J 0
(-1386 1325);
DISPLAY 0.638298 (-1386 1325);
PAINT MONO (-1386 1325);
FORCEPROP 2 LAST CDS_LIB standard
J 0
(-1575 1325);
DISPLAY INVISIBLE (-1575 1325);
FORCEPROP 1 LAST OFFPAGE TRUE
J 0
(-1250 1200);
DISPLAY 0.872340 (-1250 1200);
PAINT GREEN (-1250 1200);
DISPLAY INVISIBLE (-1250 1200);
FORCEPROP 1 LAST COMMENT_BODY TRUE
J 0
(-1620 1230);
DISPLAY 0.872340 (-1620 1230);
PAINT GREEN (-1620 1230);
DISPLAY INVISIBLE (-1620 1230);
FORCEPROP 2 LAST PATH I98
J 0
(-1375 1375);
DISPLAY 0.680851 (-1375 1375);
DISPLAY INVISIBLE (-1375 1375);
FORCEADD UNIVERSAL_GND..1
(-8700 2925);
FORCEPROP 3 LASTPIN (-8700 2975) SIG_NAME GND\g
J 0
(-8690 2985);
DISPLAY 0.659574 (-8690 2985);
PAINT MONO (-8690 2985);
DISPLAY INVISIBLE (-8690 2985);
FORCEPROP 2 LAST BOM_COST OCP3.0 
J 0
(-8900 3000);
DISPLAY 0.680851 (-8900 3000);
DISPLAY INVISIBLE (-8900 3000);
FORCEPROP 2 LAST CDS_LIB pure_quanta_power
J 0
(-8700 2925);
DISPLAY INVISIBLE (-8700 2925);
FORCEPROP 1 LAST HDL_POWER GND
J 1
(-8675 2850);
DISPLAY 0.872340 (-8675 2850);
PAINT GREEN (-8675 2850);
DISPLAY INVISIBLE (-8675 2850);
FORCEPROP 1 LAST PATH I99
J 0
(-8625 2925);
DISPLAY 0.872340 (-8625 2925);
PAINT AQUA (-8625 2925);
DISPLAY INVISIBLE (-8625 2925);
FORCEADD DNS..2
(-3575 1025);
PAINT RED (-3575 1025);
FORCEPROP 2 LAST CDS_LIB mstr_misc
J 0
(-3575 1025);
DISPLAY INVISIBLE (-3575 1025);
FORCEPROP 1 LAST COMMENT_BODY TRUE
R 1
J 0
(-3500 800);
DISPLAY 0.872340 (-3500 800);
PAINT GREEN (-3500 800);
DISPLAY INVISIBLE (-3500 800);
FORCEADD DNS..2
(-8700 3425);
PAINT RED (-8700 3425);
FORCEPROP 2 LAST CDS_LIB mstr_misc
J 0
(-8700 3425);
DISPLAY INVISIBLE (-8700 3425);
FORCEPROP 1 LAST COMMENT_BODY TRUE
R 1
J 0
(-8625 3200);
DISPLAY 0.872340 (-8625 3200);
PAINT GREEN (-8625 3200);
DISPLAY INVISIBLE (-8625 3200);
FORCEADD DNS..2
(-8350 4350);
PAINT RED (-8350 4350);
FORCEPROP 2 LAST CDS_LIB mstr_misc
J 0
(-8350 4350);
DISPLAY INVISIBLE (-8350 4350);
FORCEPROP 1 LAST COMMENT_BODY TRUE
R 1
J 0
(-8275 4125);
DISPLAY 0.872340 (-8275 4125);
PAINT GREEN (-8275 4125);
DISPLAY INVISIBLE (-8275 4125);
FORCEADD DNS..2
(-8025 4375);
PAINT RED (-8025 4375);
FORCEPROP 2 LAST CDS_LIB mstr_misc
J 0
(-8025 4375);
DISPLAY INVISIBLE (-8025 4375);
FORCEPROP 1 LAST COMMENT_BODY TRUE
R 1
J 0
(-7950 4150);
DISPLAY 0.872340 (-7950 4150);
PAINT GREEN (-7950 4150);
DISPLAY INVISIBLE (-7950 4150);
FORCEADD DNS..2
(-7375 2075);
PAINT RED (-7375 2075);
FORCEPROP 2 LAST CDS_LIB mstr_misc
J 0
(-7375 2075);
DISPLAY INVISIBLE (-7375 2075);
FORCEPROP 1 LAST COMMENT_BODY TRUE
R 1
J 0
(-7300 1850);
DISPLAY 0.872340 (-7300 1850);
PAINT GREEN (-7300 1850);
DISPLAY INVISIBLE (-7300 1850);
FORCEADD DNS..2
(-7725 2050);
PAINT RED (-7725 2050);
FORCEPROP 2 LAST CDS_LIB mstr_misc
J 0
(-7725 2050);
DISPLAY INVISIBLE (-7725 2050);
FORCEPROP 1 LAST COMMENT_BODY TRUE
R 1
J 0
(-7650 1825);
DISPLAY 0.872340 (-7650 1825);
PAINT GREEN (-7650 1825);
DISPLAY INVISIBLE (-7650 1825);
FORCEADD DNS..2
(-8100 2075);
PAINT RED (-8100 2075);
FORCEPROP 2 LAST CDS_LIB mstr_misc
J 0
(-8100 2075);
DISPLAY INVISIBLE (-8100 2075);
FORCEPROP 1 LAST COMMENT_BODY TRUE
R 1
J 0
(-8025 1850);
DISPLAY 0.872340 (-8025 1850);
PAINT GREEN (-8025 1850);
DISPLAY INVISIBLE (-8025 1850);
FORCEADD DNS..2
(-7375 4350);
PAINT RED (-7375 4350);
FORCEPROP 2 LAST CDS_LIB mstr_misc
J 0
(-7375 4350);
DISPLAY INVISIBLE (-7375 4350);
FORCEPROP 1 LAST COMMENT_BODY TRUE
R 1
J 0
(-7300 4125);
DISPLAY 0.872340 (-7300 4125);
PAINT GREEN (-7300 4125);
DISPLAY INVISIBLE (-7300 4125);
FORCEADD DNS..2
(-7725 4375);
PAINT RED (-7725 4375);
FORCEPROP 2 LAST CDS_LIB mstr_misc
J 0
(-7725 4375);
DISPLAY INVISIBLE (-7725 4375);
FORCEPROP 1 LAST COMMENT_BODY TRUE
R 1
J 0
(-7650 4150);
DISPLAY 0.872340 (-7650 4150);
PAINT GREEN (-7650 4150);
DISPLAY INVISIBLE (-7650 4150);
FORCEADD DNS..2
(-8350 2075);
PAINT RED (-8350 2075);
FORCEPROP 2 LAST CDS_LIB mstr_misc
J 0
(-8350 2075);
DISPLAY INVISIBLE (-8350 2075);
FORCEPROP 1 LAST COMMENT_BODY TRUE
R 1
J 0
(-8275 1850);
DISPLAY 0.872340 (-8275 1850);
PAINT GREEN (-8275 1850);
DISPLAY INVISIBLE (-8275 1850);
FORCEADD DNS..2
(-8700 1150);
PAINT RED (-8700 1150);
FORCEPROP 2 LAST CDS_LIB mstr_misc
J 0
(-8700 1150);
DISPLAY INVISIBLE (-8700 1150);
FORCEPROP 1 LAST COMMENT_BODY TRUE
R 1
J 0
(-8625 925);
DISPLAY 0.872340 (-8625 925);
PAINT GREEN (-8625 925);
DISPLAY INVISIBLE (-8625 925);
FORCEADD DNS..2
(-3575 3700);
PAINT RED (-3575 3700);
FORCEPROP 2 LAST CDS_LIB mstr_misc
J 0
(-3575 3700);
DISPLAY INVISIBLE (-3575 3700);
FORCEPROP 1 LAST COMMENT_BODY TRUE
R 1
J 0
(-3500 3475);
DISPLAY 0.872340 (-3500 3475);
PAINT GREEN (-3500 3475);
DISPLAY INVISIBLE (-3500 3475);
FORCEADD DNS..2
(-3200 4650);
PAINT RED (-3200 4650);
FORCEPROP 2 LAST CDS_LIB mstr_misc
J 0
(-3200 4650);
DISPLAY INVISIBLE (-3200 4650);
FORCEPROP 1 LAST COMMENT_BODY TRUE
R 1
J 0
(-3125 4425);
DISPLAY 0.872340 (-3125 4425);
PAINT GREEN (-3125 4425);
DISPLAY INVISIBLE (-3125 4425);
FORCEADD DNS..2
(-2825 4625);
PAINT RED (-2825 4625);
FORCEPROP 2 LAST CDS_LIB mstr_misc
J 0
(-2825 4625);
DISPLAY INVISIBLE (-2825 4625);
FORCEPROP 1 LAST COMMENT_BODY TRUE
R 1
J 0
(-2750 4400);
DISPLAY 0.872340 (-2750 4400);
PAINT GREEN (-2750 4400);
DISPLAY INVISIBLE (-2750 4400);
FORCEADD DNS..2
(-3225 2000);
PAINT RED (-3225 2000);
FORCEPROP 2 LAST CDS_LIB mstr_misc
J 0
(-3225 2000);
DISPLAY INVISIBLE (-3225 2000);
FORCEPROP 1 LAST COMMENT_BODY TRUE
R 1
J 0
(-3150 1775);
DISPLAY 0.872340 (-3150 1775);
PAINT GREEN (-3150 1775);
DISPLAY INVISIBLE (-3150 1775);
FORCEADD DNS..2
(-2850 2025);
PAINT RED (-2850 2025);
FORCEPROP 2 LAST CDS_LIB mstr_misc
J 0
(-2850 2025);
DISPLAY INVISIBLE (-2850 2025);
FORCEPROP 1 LAST COMMENT_BODY TRUE
R 1
J 0
(-2775 1800);
DISPLAY 0.872340 (-2775 1800);
PAINT GREEN (-2775 1800);
DISPLAY INVISIBLE (-2775 1800);
FORCEADD QUANTA_TITLE_BLOCK_C..1
(0 0);
FORCEPROP 0 LAST CDS_CON_LAST_MODIFIED Thu Sep 14 16:12:39 2023
J 0
(-1885 15);
DISPLAY INVISIBLE (-1885 15);
FORCEPROP 1 LAST CUSTOM_TXT_CDS <CON_LAST_MODIFIED>
J 0
(-1885 15);
DISPLAY 0.978723 (-1885 15);
FORCEPROP 2 LAST CUSTOM_TXT_CDS <XR_PAGE_TITLE>
J 0
(-7890 5250);
DISPLAY 0.638298 (-7890 5250);
PAINT PINK (-7890 5250);
DISPLAY INVISIBLE (-7890 5250);
FORCEPROP 1 LAST CUSTOM_TXT_CDS <NAME_2>
J 0
(-3175 50);
FORCEPROP 1 LAST CUSTOM_TXT_CDS <NAME_1>
J 0
(-3175 175);
FORCEPROP 1 LAST CUSTOM_TXT_CDS <Q_NUMBER>
J 0
(-1403 103);
DISPLAY 1.212766 (-1403 103);
FORCEPROP 1 LAST CUSTOM_TXT_CDS <Q_PROJ>
J 0
(-2382 102);
DISPLAY 1.212766 (-2382 102);
FORCEPROP 1 LAST CUSTOM_TXT_CDS <Q_REV>
J 0
(-184 103);
DISPLAY 1.212766 (-184 103);
FORCEPROP 1 LAST CUSTOM_TXT_CDS <CON_PAGE_NUM> OF <CON_TOTAL_PAGES>
J 0
(-446 18);
DISPLAY 0.978723 (-446 18);
FORCEPROP 1 LAST Q_TITLE FPGA 5/6 (BOARD ID)
J 0
(-9275 75);
DISPLAY 2.446809 (-9275 75);
PAINT GREEN (-9275 75);
FORCEPROP 2 LAST PAGE_BORDER TRUE
J 0
(-7890 5250);
DISPLAY 0.638298 (-7890 5250);
PAINT PINK (-7890 5250);
DISPLAY INVISIBLE (-7890 5250);
FORCEPROP 2 LAST CDS_LIB pure_quanta
J 0
(0 0);
DISPLAY INVISIBLE (0 0);
FORCEPROP 1 LAST CDS_LMAN_SYM_OUTLINE -9475,6775,100,-125
J 0
(0 0);
DISPLAY 0.468085 (0 0);
PAINT GREEN (0 0);
DISPLAY INVISIBLE (0 0);
FORCEPROP 2 LAST CDS_XR_PAGE_TITLE CR-84 : @T6G_MB_LIB.T6G(SCH_1):PAGE84
J 0
(-7890 5250);
DISPLAY 0.638298 (-7890 5250);
PAINT PINK (-7890 5250);
DISPLAY INVISIBLE (-7890 5250);
FORCEPROP 1 LAST Q_DEPT BU9
J 1
(-3763 49);
DISPLAY 1.957447 (-3763 49);
PAINT GREEN (-3763 49);
DISPLAY INVISIBLE (-3763 49);
FORCEPROP 1 LAST COMMENT_BODY TRUE
J 0
(12 -13);
DISPLAY 0.978723 (12 -13);
PAINT GREEN (12 -13);
DISPLAY INVISIBLE (12 -13);
WIRE 16 -1 (-8375 3300)(-8375 2975);
WIRE 16 -1 (-8050 3300)(-8050 2975);
WIRE 16 -1 (-7700 3300)(-7700 2975);
WIRE 16 -1 (-7350 3300)(-7350 2975);
WIRE 16 -1 (-8700 1025)(-8700 700);
WIRE 16 -1 (-8375 1025)(-8375 700);
WIRE 16 -1 (-8050 1025)(-8050 700);
WIRE 16 -1 (-7700 1025)(-7700 700);
WIRE 16 -1 (-7350 1025)(-7350 700);
WIRE 16 -1 (-3650 3275)(-3650 3600);
WIRE 16 -1 (-3300 3600)(-3300 3275);
WIRE 16 -1 (-2950 3600)(-2950 3275);
WIRE 16 -1 (-3650 625)(-3650 950);
WIRE 16 -1 (-3300 950)(-3300 625);
WIRE 16 -1 (-2950 950)(-2950 625);
WIRE 16 -1 (-2850 5700)(-2850 5750);
WIRE 16 -1 (-925 5875)(-925 6000);
WIRE 16 -1 (-2425 5425)(-2500 5425);
WIRE 16 -1 (-2500 5425)(-2500 5300);
WIRE 16 -1 (-8700 3300)(-8700 2975);
WIRE 16 -1 (-5650 5025)(-5650 5250);
WIRE 16 -1 (-5300 5025)(-5650 5025);
WIRE 16 -1 (-5650 5025)(-7025 5025);
WIRE 16 -1 (-5300 5250)(-5650 5250);
WIRE 16 -1 (-5650 5250)(-5650 5475);
WIRE 16 -1 (-5650 5250)(-7025 5250);
WIRE 16 -1 (-7025 5250)(-7025 5025);
WIRE 16 -1 (-7025 5475)(-7025 5250);
WIRE 16 -1 (-5650 5475)(-4275 5475);
WIRE 16 -1 (-5650 5675)(-5650 5475);
WIRE 16 -1 (-7025 5475)(-5650 5475);
WIRE 16 -1 (-5300 5025)(-5300 5250);
WIRE 16 -1 (-5300 6250)(-5300 5250);
WIRE 16 -1 (-4925 5250)(-5300 5250);
WIRE 16 -1 (-4925 5025)(-5300 5025);
WIRE 16 -1 (-4925 5025)(-4925 5250);
WIRE 16 -1 (-4575 5025)(-4925 5025);
WIRE 16 -1 (-4925 6250)(-4925 5250);
WIRE 16 -1 (-4575 5250)(-4925 5250);
WIRE 16 -1 (-4925 6250)(-5300 6250);
WIRE 16 -1 (-5300 6250)(-5650 6250);
WIRE 16 -1 (-7025 5675)(-7025 5475);
WIRE 16 -1 (-5650 5675)(-4275 5675);
WIRE 16 -1 (-5650 5875)(-5650 5675);
WIRE 16 -1 (-7025 5675)(-5650 5675);
WIRE 16 -1 (-4275 5675)(-4275 5475);
WIRE 16 -1 (-4275 5475)(-4275 5250);
WIRE 16 -1 (-4275 5250)(-4575 5250);
WIRE 16 -1 (-4275 5025)(-4275 5250);
WIRE 16 -1 (-4275 5875)(-4275 5675);
WIRE 16 -1 (-7025 5675)(-7025 5875);
WIRE 16 -1 (-5650 5875)(-4275 5875);
WIRE 16 -1 (-5650 6075)(-5650 5875);
WIRE 16 -1 (-7025 5875)(-5650 5875);
WIRE 16 -1 (-5650 6075)(-5650 6250);
WIRE 16 -1 (-7025 6250)(-5650 6250);
WIRE 16 -1 (-4575 6250)(-4925 6250);
WIRE 16 -1 (-4575 5025)(-4575 5250);
WIRE 16 -1 (-4575 6250)(-4575 5250);
WIRE 16 -1 (-4275 5025)(-4575 5025);
WIRE 16 -1 (-4275 6250)(-4575 6250);
WIRE 16 -1 (-7025 6250)(-7025 6075);
WIRE 16 -1 (-5650 6075)(-4275 6075);
WIRE 16 -1 (-5650 6075)(-7025 6075);
WIRE 16 -1 (-7025 6075)(-7025 5875);
WIRE 16 -1 (-4275 6075)(-4275 5875);
WIRE 16 -1 (-4275 6250)(-4275 6075);
WIRE 16 -1 (-7450 6225)(-7675 6225);
WIRE 16 -1 (-7450 6075)(-7450 6225);
WIRE 16 -1 (-7675 6225)(-7675 5825);
WIRE 16 -1 (-7675 6225)(-8475 6225);
WIRE 16 -1 (-8475 6225)(-8475 6075);
WIRE 16 -1 (-7450 5825)(-7675 5825);
WIRE 16 -1 (-7675 5825)(-8475 5825);
WIRE 16 -1 (-7450 6075)(-7450 5950);
WIRE 16 -1 (-7450 6075)(-8475 6075);
WIRE 16 -1 (-8475 5950)(-8475 6075);
WIRE 16 -1 (-7450 5950)(-7450 5825);
WIRE 16 -1 (-8475 5950)(-7450 5950);
WIRE 16 -1 (-8475 5825)(-8475 5950);
WIRE 16 -1 (-7350 4250)(-7350 3675);
WIRE 16 -1 (-7350 3675)(-6025 3675);
FORCEPROP 2 LAST SIG_NAME FM_BOARD_SKU_ID0
J 0
(-6725 3685);
DISPLAY 0.680851 (-6725 3685);
WIRE 16 -1 (-7350 3675)(-7350 3500);
WIRE 16 -1 (-6025 3975)(-8375 3975);
FORCEPROP 2 LAST SIG_NAME FM_BOARD_SKU_ID3
J 0
(-6725 3985);
DISPLAY 0.680851 (-6725 3985);
WIRE 16 -1 (-8375 4250)(-8375 3975);
WIRE 16 -1 (-8375 3975)(-8375 3500);
WIRE 16 -1 (-8700 4075)(-6025 4075);
FORCEPROP 2 LAST SIG_NAME FM_BOARD_SKU_ID4
J 0
(-6725 4085);
DISPLAY 0.680851 (-6725 4085);
WIRE 16 -1 (-8700 4250)(-8700 4075);
WIRE 16 -1 (-8700 4075)(-8700 3500);
WIRE 16 -1 (-7700 4250)(-7700 3775);
WIRE 16 -1 (-7700 3775)(-6025 3775);
FORCEPROP 2 LAST SIG_NAME FM_BOARD_SKU_ID1
J 0
(-6725 3785);
DISPLAY 0.680851 (-6725 3785);
WIRE 16 -1 (-7700 3775)(-7700 3500);
WIRE 16 -1 (-2950 1325)(-1625 1325);
FORCEPROP 2 LAST SIG_NAME FAB_BMC_REV_ID0
J 0
(-2350 1335);
DISPLAY 0.680851 (-2350 1335);
WIRE 16 -1 (-2950 1900)(-2950 1325);
WIRE 16 -1 (-2950 1325)(-2950 1150);
WIRE 16 -1 (-2950 2100)(-2950 2300);
WIRE 16 -1 (-3300 2300)(-2950 2300);
WIRE 16 -1 (-3300 2100)(-3300 2300);
WIRE 16 -1 (-3650 2300)(-3300 2300);
WIRE 16 -1 (-3650 2475)(-3650 2300);
WIRE 16 -1 (-3650 2300)(-3650 2100);
WIRE 16 -1 (-3300 1425)(-1625 1425);
FORCEPROP 2 LAST SIG_NAME FAB_BMC_REV_ID1
J 0
(-2350 1435);
DISPLAY 0.680851 (-2350 1435);
WIRE 16 -1 (-3300 1900)(-3300 1425);
WIRE 16 -1 (-3300 1425)(-3300 1150);
WIRE 16 -1 (-3650 1150)(-3650 1525);
WIRE 16 -1 (-1625 1525)(-3650 1525);
FORCEPROP 2 LAST SIG_NAME FAB_BMC_REV_ID2
J 0
(-2350 1535);
DISPLAY 0.680851 (-2350 1535);
WIRE 16 -1 (-3650 1525)(-3650 1900);
WIRE 16 -1 (-3650 5125)(-3650 4950);
WIRE 16 -1 (-3650 4950)(-3300 4950);
WIRE 16 -1 (-3650 4950)(-3650 4750);
WIRE 16 -1 (-3300 4950)(-2950 4950);
WIRE 16 -1 (-3300 4750)(-3300 4950);
WIRE 16 -1 (-2950 4750)(-2950 4950);
WIRE 16 -1 (-8700 4450)(-8700 4650);
WIRE 16 -1 (-8700 4650)(-8375 4650);
WIRE 16 -1 (-8700 4825)(-8700 4650);
WIRE 16 -1 (-8375 4650)(-8050 4650);
WIRE 16 -1 (-8375 4450)(-8375 4650);
WIRE 16 -1 (-8050 4650)(-7700 4650);
WIRE 16 -1 (-8050 4450)(-8050 4650);
WIRE 16 -1 (-7700 4650)(-7350 4650);
WIRE 16 -1 (-7700 4450)(-7700 4650);
WIRE 16 -1 (-7350 4450)(-7350 4650);
WIRE 16 -1 (-8700 2175)(-8700 2375);
WIRE 16 -1 (-8700 2375)(-8375 2375);
WIRE 16 -1 (-8700 2550)(-8700 2375);
WIRE 16 -1 (-8375 2375)(-8050 2375);
WIRE 16 -1 (-8375 2175)(-8375 2375);
WIRE 16 -1 (-8050 2375)(-7700 2375);
WIRE 16 -1 (-8050 2175)(-8050 2375);
WIRE 16 -1 (-7700 2375)(-7350 2375);
WIRE 16 -1 (-7700 2175)(-7700 2375);
WIRE 16 -1 (-7350 2175)(-7350 2375);
WIRE 16 -1 (-2500 6000)(-2500 5625);
WIRE 16 -1 (-2850 6000)(-2500 6000);
WIRE 16 -1 (-2500 5625)(-2425 5625);
WIRE 16 -1 (-2850 6000)(-2850 5950);
WIRE 16 -1 (-2850 6100)(-2850 6000);
WIRE 16 -1 (-2850 6000)(-2975 6000);
WIRE 16 -1 (-2975 5950)(-2975 6000);
WIRE 16 -1 (-1625 4175)(-3650 4175);
FORCEPROP 2 LAST SIG_NAME FAB_REV_ID2
J 0
(-2350 4185);
DISPLAY 0.680851 (-2350 4185);
WIRE 16 -1 (-3650 4175)(-3650 4550);
WIRE 16 -1 (-3650 3800)(-3650 4175);
WIRE 16 -1 (-3300 4550)(-3300 4075);
WIRE 16 -1 (-3300 4075)(-1625 4075);
FORCEPROP 2 LAST SIG_NAME FAB_REV_ID1
J 0
(-2350 4085);
DISPLAY 0.680851 (-2350 4085);
WIRE 16 -1 (-3300 4075)(-3300 3800);
WIRE 16 -1 (-2950 4550)(-2950 3975);
WIRE 16 -1 (-2950 3975)(-1625 3975);
FORCEPROP 2 LAST SIG_NAME FAB_REV_ID0
J 0
(-2350 3985);
DISPLAY 0.680851 (-2350 3985);
WIRE 16 -1 (-2950 3975)(-2950 3800);
WIRE 16 -1 (-1925 2300)(-1925 2575);
WIRE 16 -1 (-1925 2300)(-1575 2300);
WIRE 16 -1 (-1575 2575)(-1925 2575);
WIRE 16 -1 (-1925 2575)(-1925 2850);
WIRE 16 -1 (-1925 2850)(-550 2850);
WIRE 16 -1 (-1925 3050)(-1925 2850);
WIRE 16 -1 (-1575 2575)(-1575 2300);
WIRE 16 -1 (-1575 3625)(-1575 2575);
WIRE 16 -1 (-1200 2575)(-1575 2575);
WIRE 16 -1 (-1575 2300)(-1200 2300);
WIRE 16 -1 (-1200 2575)(-1200 2300);
WIRE 16 -1 (-850 2300)(-1200 2300);
WIRE 16 -1 (-850 2575)(-1200 2575);
WIRE 16 -1 (-1200 3625)(-1200 2575);
WIRE 16 -1 (-1200 3625)(-1575 3625);
WIRE 16 -1 (-1575 3625)(-1925 3625);
WIRE 16 -1 (-1925 3050)(-550 3050);
WIRE 16 -1 (-1925 3250)(-1925 3050);
WIRE 16 -1 (-550 3050)(-550 2850);
WIRE 16 -1 (-550 2850)(-550 2575);
WIRE 16 -1 (-550 2575)(-850 2575);
WIRE 16 -1 (-550 2575)(-550 2300);
WIRE 16 -1 (-550 3250)(-550 3050);
WIRE 16 -1 (-1925 3250)(-550 3250);
WIRE 16 -1 (-1925 3450)(-1925 3250);
WIRE 16 -1 (-1925 3450)(-1925 3625);
WIRE 16 -1 (-850 3625)(-1200 3625);
WIRE 16 -1 (-850 2575)(-850 2300);
WIRE 16 -1 (-850 3625)(-850 2575);
WIRE 16 -1 (-550 2300)(-850 2300);
WIRE 16 -1 (-550 3625)(-850 3625);
WIRE 16 -1 (-1925 3450)(-550 3450);
WIRE 16 -1 (-550 3450)(-550 3250);
WIRE 16 -1 (-550 3625)(-550 3450);
WIRE 16 -1 (-6025 3875)(-8050 3875);
FORCEPROP 2 LAST SIG_NAME FM_BOARD_SKU_ID2
J 0
(-6725 3885);
DISPLAY 0.680851 (-6725 3885);
WIRE 16 -1 (-8050 3875)(-8050 4250);
WIRE 16 -1 (-8050 3500)(-8050 3875);
WIRE 16 -1 (-1400 5525)(-925 5525);
FORCEPROP 2 LAST SIG_NAME SCM_IRQ_N
J 0
(-1260 5535);
DISPLAY 0.489362 (-1260 5535);
WIRE 16 -1 (-925 5525)(-925 5675);
WIRE 16 -1 (-925 5525)(-825 5525);
WIRE 16 -1 (-2075 5525)(-1600 5525);
FORCEPROP 2 LAST SIG_NAME SCM_IRQ_R_N
J 0
(-1935 5535);
DISPLAY 0.489362 (-1935 5535);
FORCEPROP 2 LASTPROP $XRERR UNIQUE?
J 0
(-2175 5535);
DISPLAY 0.638298 (-2175 5535);
PAINT MONO (-2175 5535);
DISPLAY INVISIBLE (-2175 5535);
WIRE 16 -1 (-3700 5525)(-2975 5525);
FORCEPROP 2 LAST SIG_NAME SCM_IRQ_1V8_N
J 0
(-3685 5535);
DISPLAY 0.489362 (-3685 5535);
WIRE 16 -1 (-2975 5525)(-2425 5525);
WIRE 16 -1 (-2975 5525)(-2975 5750);
WIRE 16 -1 (-6025 1600)(-8050 1600);
FORCEPROP 2 LAST SIG_NAME FM_BOARD_BMC_SKU_ID2
J 0
(-6725 1610);
DISPLAY 0.680851 (-6725 1610);
WIRE 16 -1 (-8050 1600)(-8050 1975);
WIRE 16 -1 (-8050 1225)(-8050 1600);
WIRE 16 -1 (-7700 1500)(-6025 1500);
FORCEPROP 2 LAST SIG_NAME FM_BOARD_BMC_SKU_ID1
J 0
(-6725 1510);
DISPLAY 0.680851 (-6725 1510);
WIRE 16 -1 (-7700 1975)(-7700 1500);
WIRE 16 -1 (-7700 1500)(-7700 1225);
WIRE 16 -1 (-7350 1400)(-6025 1400);
FORCEPROP 2 LAST SIG_NAME FM_BOARD_BMC_SKU_ID0
J 0
(-6725 1410);
DISPLAY 0.680851 (-6725 1410);
WIRE 16 -1 (-7350 1975)(-7350 1400);
WIRE 16 -1 (-7350 1400)(-7350 1225);
WIRE 16 -1 (-6025 1700)(-8375 1700);
FORCEPROP 2 LAST SIG_NAME FM_BOARD_BMC_SKU_ID3
J 0
(-6725 1710);
DISPLAY 0.680851 (-6725 1710);
WIRE 16 -1 (-8375 1975)(-8375 1700);
WIRE 16 -1 (-8375 1700)(-8375 1225);
WIRE 16 -1 (-8700 1800)(-6025 1800);
FORCEPROP 2 LAST SIG_NAME FM_BOARD_BMC_SKU_ID4
J 0
(-6725 1810);
DISPLAY 0.680851 (-6725 1810);
WIRE 16 -1 (-8700 1975)(-8700 1800);
WIRE 16 -1 (-8700 1800)(-8700 1225);
DOT 1 (-4925 6250);
CIRCLE (-6525 2700)(-6154 2700);
PAINT YELLOW (-6525 2700);
DOT 1 (-2950 1325);
DOT 1 (-3300 1425);
DOT 1 (-3300 2300);
DOT 1 (-3650 1525);
DOT 1 (-2950 3975);
DOT 1 (-3650 4175);
DOT 1 (-3300 4075);
DOT 1 (-3300 4950);
DOT 1 (-1925 2575);
DOT 1 (-1925 3450);
DOT 1 (-550 2575);
DOT 1 (-850 2300);
DOT 1 (-850 2575);
DOT 1 (-1200 2575);
DOT 1 (-1200 2300);
DOT 1 (-1575 2300);
DOT 1 (-1200 3625);
DOT 1 (-1575 2575);
DOT 1 (-1925 3250);
DOT 1 (-1575 3625);
DOT 1 (-1925 2850);
DOT 1 (-1925 3050);
DOT 1 (-850 3625);
DOT 1 (-550 3050);
DOT 1 (-550 2850);
DOT 1 (-550 3450);
DOT 1 (-550 3250);
DOT 1 (-3650 4950);
DOT 1 (-4275 5675);
DOT 1 (-4575 6250);
DOT 1 (-4925 5250);
DOT 1 (-5650 5875);
DOT 1 (-7025 5475);
DOT 1 (-8050 4650);
DOT 1 (-8375 4650);
DOT 1 (-7350 1400);
DOT 1 (-8475 5950);
DOT 1 (-8475 6075);
DOT 1 (-7675 5825);
DOT 1 (-7675 6225);
DOT 1 (-7450 5950);
DOT 1 (-7450 6075);
DOT 1 (-7025 5675);
DOT 1 (-7025 5875);
DOT 1 (-7025 6075);
DOT 1 (-5650 5475);
DOT 1 (-5650 5675);
DOT 1 (-5650 6075);
DOT 1 (-5300 6250);
DOT 1 (-4275 5875);
DOT 1 (-4275 6075);
DOT 1 (-7700 2375);
DOT 1 (-7700 4650);
DOT 1 (-3650 2300);
DOT 1 (-7700 3775);
DOT 1 (-7700 1500);
DOT 1 (-8700 4650);
DOT 1 (-8050 2375);
DOT 1 (-925 5525);
DOT 1 (-2850 6000);
DOT 1 (-2975 5525);
DOT 1 (-8700 2375);
DOT 1 (-7350 3675);
DOT 1 (-8700 4075);
DOT 1 (-8050 3875);
DOT 1 (-8700 1800);
DOT 1 (-8375 2375);
DOT 1 (-8375 1700);
DOT 1 (-8375 3975);
DOT 1 (-8050 1600);
DOT 1 (-7025 5250);
DOT 1 (-5650 5250);
DOT 1 (-4575 5250);
DOT 1 (-5300 5250);
DOT 1 (-5650 5025);
DOT 1 (-5300 5025);
DOT 1 (-4925 5025);
DOT 1 (-4575 5025);
DOT 1 (-4275 5250);
DOT 1 (-4275 5475);
DOT 1 (-5650 6250);
FORCENOTE
ID1
(-4825 6150) 0;
DISPLAY LEFT (-4825 6150);
DISPLAY 1.021277 (-4825 6150);
PAINT WHITE (-4825 6150);
FORCENOTE
HSC-MPS5990+ADC-TIC+VR-MPS
(-6975 5125) 0;
DISPLAY LEFT (-6975 5125);
DISPLAY 1.021277 (-6975 5125);
PAINT WHITE (-6975 5125);
FORCENOTE
HSC-MODULE+ADC-MAM+VR-MPS
(-6975 5350) 0;
DISPLAY LEFT (-6975 5350);
DISPLAY 1.021277 (-6975 5350);
PAINT WHITE (-6975 5350);
FORCENOTE
HSC-REEDSEMI+ADC-TIC+VR-RTT
(-6975 5550) 0;
DISPLAY LEFT (-6975 5550);
DISPLAY 1.021277 (-6975 5550);
PAINT WHITE (-6975 5550);
FORCENOTE
HSC-MODULE+ADC-MAM+VR-SNI
(-6975 5750) 0;
DISPLAY LEFT (-6975 5750);
DISPLAY 1.021277 (-6975 5750);
PAINT WHITE (-6975 5750);
FORCENOTE
HSC-MPS5990+ADC-TIC+VR-RTT
(-6975 5950) 0;
DISPLAY LEFT (-6975 5950);
DISPLAY 1.021277 (-6975 5950);
PAINT WHITE (-6975 5950);
FORCENOTE
PVT2
(-1825 2425) 0;
DISPLAY LEFT (-1825 2425);
DISPLAY 1.021277 (-1825 2425);
PAINT WHITE (-1825 2425);
FORCENOTE
DVT2
(-1825 2925) 0;
DISPLAY LEFT (-1825 2925);
DISPLAY 1.021277 (-1825 2925);
PAINT WHITE (-1825 2925);
FORCENOTE
0
(-1375 3125) 0;
DISPLAY LEFT (-1375 3125);
DISPLAY 1.021277 (-1375 3125);
PAINT WHITE (-1375 3125);
FORCENOTE
0
(-1375 2925) 0;
DISPLAY LEFT (-1375 2925);
DISPLAY 1.021277 (-1375 2925);
PAINT WHITE (-1375 2925);
FORCENOTE
0
(-1375 2675) 0;
DISPLAY LEFT (-1375 2675);
DISPLAY 1.021277 (-1375 2675);
PAINT WHITE (-1375 2675);
FORCENOTE
1
(-1050 2675) 0;
DISPLAY LEFT (-1050 2675);
DISPLAY 1.021277 (-1050 2675);
PAINT WHITE (-1050 2675);
FORCENOTE
2 RT
(-2125 2950) 0;
DISPLAY LEFT (-2125 2950);
DISPLAY 1.021277 (-2125 2950);
PAINT WHITE (-2125 2950);
FORCENOTE
8 RT
(-2125 3125) 0;
DISPLAY LEFT (-2125 3125);
DISPLAY 1.021277 (-2125 3125);
PAINT WHITE (-2125 3125);
FORCENOTE
ID2
(-1450 3525) 0;
DISPLAY LEFT (-1450 3525);
DISPLAY 1.021277 (-1450 3525);
PAINT WHITE (-1450 3525);
FORCENOTE
0
(-700 2425) 0;
DISPLAY LEFT (-700 2425);
DISPLAY 1.021277 (-700 2425);
PAINT WHITE (-700 2425);
FORCENOTE
0
(-1050 2425) 0;
DISPLAY LEFT (-1050 2425);
DISPLAY 1.021277 (-1050 2425);
PAINT WHITE (-1050 2425);
FORCENOTE
1
(-1375 2425) 0;
DISPLAY LEFT (-1375 2425);
DISPLAY 1.021277 (-1375 2425);
PAINT WHITE (-1375 2425);
FORCENOTE
0
(-700 2925) 0;
DISPLAY LEFT (-700 2925);
DISPLAY 1.021277 (-700 2925);
PAINT WHITE (-700 2925);
FORCENOTE
PVT1
(-1825 2675) 0;
DISPLAY LEFT (-1825 2675);
DISPLAY 1.021277 (-1825 2675);
PAINT WHITE (-1825 2675);
FORCENOTE
EVT
(-1825 3300) 0;
DISPLAY LEFT (-1825 3300);
DISPLAY 1.021277 (-1825 3300);
PAINT WHITE (-1825 3300);
FORCENOTE
REV
(-1800 3525) 0;
DISPLAY LEFT (-1800 3525);
DISPLAY 1.021277 (-1800 3525);
PAINT WHITE (-1800 3525);
FORCENOTE
0
(-1375 3325) 0;
DISPLAY LEFT (-1375 3325);
DISPLAY 1.021277 (-1375 3325);
PAINT WHITE (-1375 3325);
FORCENOTE
0
(-1050 3325) 0;
DISPLAY LEFT (-1050 3325);
DISPLAY 1.021277 (-1050 3325);
PAINT WHITE (-1050 3325);
FORCENOTE
ID1
(-1100 3525) 0;
DISPLAY LEFT (-1100 3525);
DISPLAY 1.021277 (-1100 3525);
PAINT WHITE (-1100 3525);
FORCENOTE
0
(-1050 3125) 0;
DISPLAY LEFT (-1050 3125);
DISPLAY 1.021277 (-1050 3125);
PAINT WHITE (-1050 3125);
FORCENOTE
1
(-700 3125) 0;
DISPLAY LEFT (-700 3125);
DISPLAY 1.021277 (-700 3125);
PAINT WHITE (-700 3125);
FORCENOTE
ID0
(-775 3525) 0;
DISPLAY LEFT (-775 3525);
DISPLAY 1.021277 (-775 3525);
PAINT WHITE (-775 3525);
FORCENOTE
0
(-700 3325) 0;
DISPLAY LEFT (-700 3325);
DISPLAY 1.021277 (-700 3325);
PAINT WHITE (-700 3325);
FORCENOTE
1
(-700 2675) 0;
DISPLAY LEFT (-700 2675);
DISPLAY 1.021277 (-700 2675);
PAINT WHITE (-700 2675);
FORCENOTE
1
(-1050 2925) 0;
DISPLAY LEFT (-1050 2925);
DISPLAY 1.021277 (-1050 2925);
PAINT WHITE (-1050 2925);
FORCENOTE
DVT1
(-1825 3125) 0;
DISPLAY LEFT (-1825 3125);
DISPLAY 1.021277 (-1825 3125);
PAINT WHITE (-1825 3125);
FORCENOTE
ID0
(-4500 6150) 0;
DISPLAY LEFT (-4500 6150);
DISPLAY 1.021277 (-4500 6150);
PAINT WHITE (-4500 6150);
FORCENOTE
0
(-4775 5750) 0;
DISPLAY LEFT (-4775 5750);
DISPLAY 1.021277 (-4775 5750);
PAINT WHITE (-4775 5750);
FORCENOTE
0
(-4425 5750) 0;
DISPLAY LEFT (-4425 5750);
DISPLAY 1.021277 (-4425 5750);
PAINT RED (-4425 5750);
FORCENOTE
0
(-4425 5950) 0;
DISPLAY LEFT (-4425 5950);
DISPLAY 1.021277 (-4425 5950);
PAINT WHITE (-4425 5950);
FORCENOTE
0
(-4775 5950) 0;
DISPLAY LEFT (-4775 5950);
DISPLAY 1.021277 (-4775 5950);
PAINT WHITE (-4775 5950);
FORCENOTE
AMD PLATFORM
(-8350 5850) 0;
DISPLAY LEFT (-8350 5850);
DISPLAY 1.021277 (-8350 5850);
PAINT WHITE (-8350 5850);
FORCENOTE
0
(-4425 5550) 0;
DISPLAY LEFT (-4425 5550);
DISPLAY 1.021277 (-4425 5550);
PAINT WHITE (-4425 5550);
FORCENOTE
BRD_SKU
(-8225 6125) 0;
DISPLAY LEFT (-8225 6125);
DISPLAY 1.021277 (-8225 6125);
PAINT WHITE (-8225 6125);
FORCENOTE
INTEL PLATFORM
(-8400 5975) 0;
DISPLAY LEFT (-8400 5975);
DISPLAY 1.021277 (-8400 5975);
PAINT WHITE (-8400 5975);
FORCENOTE
0
(-7600 5975) 0;
DISPLAY LEFT (-7600 5975);
DISPLAY 1.021277 (-7600 5975);
PAINT WHITE (-7600 5975);
FORCENOTE
ID4
(-7625 6125) 0;
DISPLAY LEFT (-7625 6125);
DISPLAY 1.021277 (-7625 6125);
PAINT WHITE (-7625 6125);
FORCENOTE
1
(-7600 5850) 0;
DISPLAY LEFT (-7600 5850);
DISPLAY 1.021277 (-7600 5850);
PAINT WHITE (-7600 5850);
FORCENOTE
0
(-5100 5550) 0;
DISPLAY LEFT (-5100 5550);
DISPLAY 1.021277 (-5100 5550);
PAINT WHITE (-5100 5550);
FORCENOTE
0
(-5100 5950) 0;
DISPLAY LEFT (-5100 5950);
DISPLAY 1.021277 (-5100 5950);
PAINT WHITE (-5100 5950);
FORCENOTE
1
(-4775 5550) 0;
DISPLAY LEFT (-4775 5550);
DISPLAY 1.021277 (-4775 5550);
PAINT WHITE (-4775 5550);
FORCENOTE
BRD_SKU
(-6475 6150) 0;
DISPLAY LEFT (-6475 6150);
DISPLAY 1.021277 (-6475 6150);
PAINT WHITE (-6475 6150);
FORCENOTE
TBC
(-6600 2900) 0;
DISPLAY LEFT (-6600 2900);
DISPLAY 1.021277 (-6600 2900);
FORCENOTE
ID3
(-5525 6150) 0;
DISPLAY LEFT (-5525 6150);
DISPLAY 1.021277 (-5525 6150);
PAINT WHITE (-5525 6150);
FORCENOTE
ID2
(-5175 6150) 0;
DISPLAY LEFT (-5175 6150);
DISPLAY 1.021277 (-5175 6150);
PAINT WHITE (-5175 6150);
FORCENOTE
0
(-5475 5750) 0;
DISPLAY LEFT (-5475 5750);
DISPLAY 1.021277 (-5475 5750);
PAINT WHITE (-5475 5750);
FORCENOTE
0
(-4425 5325) 0;
DISPLAY LEFT (-4425 5325);
DISPLAY 1.021277 (-4425 5325);
PAINT RED (-4425 5325);
FORCENOTE
0
(-5475 5550) 0;
DISPLAY LEFT (-5475 5550);
DISPLAY 1.021277 (-5475 5550);
PAINT WHITE (-5475 5550);
FORCENOTE
1
(-5100 5750) 0;
DISPLAY LEFT (-5100 5750);
DISPLAY 1.021277 (-5100 5750);
PAINT RED (-5100 5750);
FORCENOTE
0
(-5475 5125) 0;
DISPLAY LEFT (-5475 5125);
DISPLAY 1.021277 (-5475 5125);
PAINT WHITE (-5475 5125);
FORCENOTE
0
(-5100 5125) 0;
DISPLAY LEFT (-5100 5125);
DISPLAY 1.021277 (-5100 5125);
PAINT WHITE (-5100 5125);
FORCENOTE
0
(-4775 5125) 0;
DISPLAY LEFT (-4775 5125);
DISPLAY 1.021277 (-4775 5125);
PAINT WHITE (-4775 5125);
FORCENOTE
0
(-5475 5950) 0;
DISPLAY LEFT (-5475 5950);
DISPLAY 1.021277 (-5475 5950);
PAINT WHITE (-5475 5950);
FORCENOTE
1
(-4775 5325) 0;
DISPLAY LEFT (-4775 5325);
DISPLAY 1.021277 (-4775 5325);
PAINT WHITE (-4775 5325);
FORCENOTE
0
(-5475 5325) 0;
DISPLAY LEFT (-5475 5325);
DISPLAY 1.021277 (-5475 5325);
PAINT WHITE (-5475 5325);
FORCENOTE
1
(-5100 5325) 0;
DISPLAY LEFT (-5100 5325);
DISPLAY 1.021277 (-5100 5325);
PAINT RED (-5100 5325);
FORCENOTE
1
(-4425 5125) 0;
DISPLAY LEFT (-4425 5125);
DISPLAY 1.021277 (-4425 5125);
PAINT RED (-4425 5125);
QUIT
